FILE_TYPE = MACRO_DRAWING;
SET COLOR_WIRE YELLOW;
SET COLOR_PROP ORANGE;
SET COLOR_DOT WHITE;
SET COLOR_ARC YELLOW;
SET COLOR_BODY GREEN;
SET COLOR_NOTE PURPLE;
SET PROP_DISPLAY VALUE;
SET PAGE_NUMBER P29;
FORCEADD OFFPAGE..2
(-6850 2775);
FORCEPROP 2 LAST $XR2 117 
J 0
(-6481 2775);
DISPLAY 0.638298 (-6481 2775);
PAINT MONO (-6481 2775);
FORCEPROP 2 LAST $XR1 80 
J 0
(-6571 2775);
DISPLAY 0.638298 (-6571 2775);
PAINT MONO (-6571 2775);
FORCEPROP 2 LAST $XR0 29 
J 0
(-6661 2775);
DISPLAY 0.638298 (-6661 2775);
PAINT MONO (-6661 2775);
FORCEPROP 2 LAST CDS_LIB standard
J 0
(-6850 2775);
DISPLAY INVISIBLE (-6850 2775);
FORCEPROP 1 LAST OFFPAGE TRUE
J 0
(-6525 2650);
DISPLAY 0.872340 (-6525 2650);
PAINT GREEN (-6525 2650);
DISPLAY INVISIBLE (-6525 2650);
FORCEPROP 1 LAST COMMENT_BODY TRUE
J 0
(-6895 2680);
DISPLAY 0.872340 (-6895 2680);
PAINT PEACH (-6895 2680);
DISPLAY INVISIBLE (-6895 2680);
FORCEPROP 2 LAST PATH I276
J 0
(-6550 2825);
DISPLAY 1.021277 (-6550 2825);
DISPLAY INVISIBLE (-6550 2825);
FORCEADD UNIVERSAL_POWER..1
(-7925 3675);
FORCEPROP 3 LASTPIN (-7925 3625) SIG_NAME PVDD18_S5_P0\g
J 0
(-7915 3635);
DISPLAY 0.659574 (-7915 3635);
PAINT MONO (-7915 3635);
DISPLAY INVISIBLE (-7915 3635);
FORCEPROP 1 LAST HDL_POWER PVDD18_S5_P0
J 1
(-7925 3725);
DISPLAY 0.489362 (-7925 3725);
PAINT GREEN (-7925 3725);
FORCEPROP 1 LAST PATH I277
J 0
(-7875 3700);
DISPLAY 0.872340 (-7875 3700);
PAINT AQUA (-7875 3700);
DISPLAY INVISIBLE (-7875 3700);
FORCEPROP 2 LAST CDS_LIB pure_quanta_power
J 0
(-7925 3675);
DISPLAY INVISIBLE (-7925 3675);
FORCEADD OFFPAGE..2
(-6850 2875);
FORCEPROP 2 LAST $XR2 117 
J 0
(-6481 2875);
DISPLAY 0.638298 (-6481 2875);
PAINT MONO (-6481 2875);
FORCEPROP 2 LAST $XR1 80 
J 0
(-6571 2875);
DISPLAY 0.638298 (-6571 2875);
PAINT MONO (-6571 2875);
FORCEPROP 2 LAST $XR0 29 
J 0
(-6661 2875);
DISPLAY 0.638298 (-6661 2875);
PAINT MONO (-6661 2875);
FORCEPROP 2 LAST CDS_LIB standard
J 0
(-6850 2875);
DISPLAY INVISIBLE (-6850 2875);
FORCEPROP 1 LAST OFFPAGE TRUE
J 0
(-6525 2750);
DISPLAY 0.872340 (-6525 2750);
PAINT GREEN (-6525 2750);
DISPLAY INVISIBLE (-6525 2750);
FORCEPROP 1 LAST COMMENT_BODY TRUE
J 0
(-6895 2780);
DISPLAY 0.872340 (-6895 2780);
PAINT PEACH (-6895 2780);
DISPLAY INVISIBLE (-6895 2780);
FORCEPROP 2 LAST PATH I280
J 0
(-6550 2925);
DISPLAY 1.021277 (-6550 2925);
DISPLAY INVISIBLE (-6550 2925);
FORCEADD Q_RES..2
(-7925 3225);
FORCEPROP 1 LAST LOCATION R457
J 0
(-7880 3350);
DISPLAY 0.489362 (-7880 3350);
PAINT SKYBLUE (-7880 3350);
FORCEPROP 0 LAST $SEC 1
J 0
(-7875 3400);
DISPLAY 0.680851 (-7875 3400);
PAINT MONO (-7875 3400);
DISPLAY INVISIBLE (-7875 3400);
FORCEPROP 0 LAST CDS_SEC 1
J 0
(-7875 3400);
DISPLAY 1.021277 (-7875 3400);
DISPLAY INVISIBLE (-7875 3400);
FORCEPROP 1 LASTPIN (-7925 3325) $PN 1
J 0
(-7920 3287);
DISPLAY 0.489362 (-7920 3287);
PAINT MONO (-7920 3287);
FORCEPROP 1 LASTPIN (-7925 3125) $PN 2
J 0
(-7920 3135);
DISPLAY 0.489362 (-7920 3135);
PAINT MONO (-7920 3135);
FORCEPROP 1 LAST TOLERANCE 5%
J 0
(-7880 3250);
DISPLAY 0.489362 (-7880 3250);
PAINT SKYBLUE (-7880 3250);
FORCEPROP 1 LAST PACK_TYPE 0402LF
J 0
(-7875 3100);
DISPLAY 0.489362 (-7875 3100);
PAINT SKYBLUE (-7875 3100);
FORCEPROP 1 LAST VALUE 4.7K
J 0
(-7880 3300);
DISPLAY 0.489362 (-7880 3300);
PAINT SKYBLUE (-7880 3300);
FORCEPROP 1 LAST MATERIAL CHIP
J 0
(-7885 3150);
DISPLAY 0.489362 (-7885 3150);
PAINT SKYBLUE (-7885 3150);
FORCEPROP 1 LAST WATTAGE 1/16W
J 0
(-7885 3200);
DISPLAY 0.489362 (-7885 3200);
PAINT SKYBLUE (-7885 3200);
FORCEPROP 1 LAST PART_NUMBER TMP_QCS24702JB38
J 0
(-7885 3100);
DISPLAY 0.489362 (-7885 3100);
PAINT SKYBLUE (-7885 3100);
DISPLAY INVISIBLE (-7885 3100);
FORCEPROP 1 LAST PATH I282
J 0
(-7875 3400);
DISPLAY 0.978723 (-7875 3400);
PAINT WHITE (-7875 3400);
DISPLAY INVISIBLE (-7875 3400);
FORCEPROP 2 LAST CDS_LIB pure_quanta
J 0
(-7925 3225);
DISPLAY INVISIBLE (-7925 3225);
FORCEADD Q_RES..2
(-8150 3250);
FORCEPROP 1 LAST LOCATION R455
J 0
(-8105 3375);
DISPLAY 0.489362 (-8105 3375);
PAINT SKYBLUE (-8105 3375);
FORCEPROP 0 LAST $SEC 1
J 0
(-8100 3425);
DISPLAY 0.680851 (-8100 3425);
PAINT MONO (-8100 3425);
DISPLAY INVISIBLE (-8100 3425);
FORCEPROP 0 LAST CDS_SEC 1
J 0
(-8100 3425);
DISPLAY 1.021277 (-8100 3425);
DISPLAY INVISIBLE (-8100 3425);
FORCEPROP 1 LASTPIN (-8150 3350) $PN 1
J 0
(-8145 3312);
DISPLAY 0.489362 (-8145 3312);
PAINT MONO (-8145 3312);
FORCEPROP 1 LASTPIN (-8150 3150) $PN 2
J 0
(-8145 3160);
DISPLAY 0.489362 (-8145 3160);
PAINT MONO (-8145 3160);
FORCEPROP 1 LAST PACK_TYPE 0402LF
J 0
(-8100 3125);
DISPLAY 0.489362 (-8100 3125);
PAINT SKYBLUE (-8100 3125);
FORCEPROP 1 LAST VALUE 4.7K
J 0
(-8105 3325);
DISPLAY 0.489362 (-8105 3325);
PAINT SKYBLUE (-8105 3325);
FORCEPROP 1 LAST TOLERANCE 5%
J 0
(-8105 3275);
DISPLAY 0.489362 (-8105 3275);
PAINT SKYBLUE (-8105 3275);
FORCEPROP 1 LAST WATTAGE 1/16W
J 0
(-8110 3225);
DISPLAY 0.489362 (-8110 3225);
PAINT SKYBLUE (-8110 3225);
FORCEPROP 1 LAST MATERIAL CHIP
J 0
(-8110 3175);
DISPLAY 0.489362 (-8110 3175);
PAINT SKYBLUE (-8110 3175);
FORCEPROP 1 LAST PART_NUMBER TMP_QCS24702JB38
J 0
(-8110 3125);
DISPLAY 0.489362 (-8110 3125);
PAINT SKYBLUE (-8110 3125);
DISPLAY INVISIBLE (-8110 3125);
FORCEPROP 1 LAST PATH I284
J 0
(-8100 3425);
DISPLAY 0.978723 (-8100 3425);
PAINT WHITE (-8100 3425);
DISPLAY INVISIBLE (-8100 3425);
FORCEPROP 2 LAST CDS_LIB pure_quanta
J 0
(-8150 3250);
DISPLAY INVISIBLE (-8150 3250);
FORCEADD GENOA_SP5..22
(-4675 4825);
FORCEPROP 1 LAST LOCATION U25
J 0
(-5770 6356);
DISPLAY 0.489362 (-5770 6356);
PAINT SKYBLUE (-5770 6356);
FORCEPROP 0 LAST $SEC 22
J 0
(-5750 6400);
DISPLAY 0.680851 (-5750 6400);
PAINT MONO (-5750 6400);
DISPLAY INVISIBLE (-5750 6400);
FORCEPROP 0 LAST CDS_SEC 22
J 0
(-5775 6400);
DISPLAY 1.021277 (-5775 6400);
DISPLAY INVISIBLE (-5775 6400);
FORCEPROP 0 LASTPIN (-5925 4250) $PN DJ25
J 2
(-5935 4260);
DISPLAY 0.489362 (-5935 4260);
PAINT MONO (-5935 4260);
FORCEPROP 0 LASTPIN (-5925 4500) $PN DJ22
J 2
(-5935 4510);
DISPLAY 0.489362 (-5935 4510);
PAINT MONO (-5935 4510);
FORCEPROP 0 LASTPIN (-5925 5250) $PN DF28
J 2
(-5935 5260);
DISPLAY 0.489362 (-5935 5260);
PAINT MONO (-5935 5260);
FORCEPROP 0 LASTPIN (-5925 5200) $PN DG22
J 2
(-5935 5210);
DISPLAY 0.489362 (-5935 5210);
PAINT MONO (-5935 5210);
FORCEPROP 0 LASTPIN (-5925 5150) $PN DJ28
J 2
(-5935 5160);
DISPLAY 0.489362 (-5935 5160);
PAINT MONO (-5935 5160);
FORCEPROP 0 LASTPIN (-5925 5100) $PN DG29
J 2
(-5935 5110);
DISPLAY 0.489362 (-5935 5110);
PAINT MONO (-5935 5110);
FORCEPROP 0 LASTPIN (-5925 4650) $PN DF24
J 2
(-5935 4660);
DISPLAY 0.489362 (-5935 4660);
PAINT MONO (-5935 4660);
FORCEPROP 0 LASTPIN (-5925 4950) $PN DH24
J 2
(-5935 4960);
DISPLAY 0.489362 (-5935 4960);
PAINT MONO (-5935 4960);
FORCEPROP 0 LASTPIN (-5925 4900) $PN DE24
J 2
(-5935 4910);
DISPLAY 0.489362 (-5935 4910);
PAINT MONO (-5935 4910);
FORCEPROP 0 LASTPIN (-5925 4850) $PN DF25
J 2
(-5935 4860);
DISPLAY 0.489362 (-5935 4860);
PAINT MONO (-5935 4860);
FORCEPROP 0 LASTPIN (-5925 4800) $PN DG25
J 2
(-5935 4810);
DISPLAY 0.489362 (-5935 4810);
PAINT MONO (-5935 4810);
FORCEPROP 0 LASTPIN (-5925 5650) $PN DJ27
J 2
(-5935 5660);
DISPLAY 0.489362 (-5935 5660);
PAINT MONO (-5935 5660);
FORCEPROP 0 LASTPIN (-5925 4450) $PN DG23
J 2
(-5935 4460);
DISPLAY 0.489362 (-5935 4460);
PAINT MONO (-5935 4460);
FORCEPROP 0 LASTPIN (-5925 4400) $PN DF27
J 2
(-5935 4410);
DISPLAY 0.489362 (-5935 4410);
PAINT MONO (-5935 4410);
FORCEPROP 0 LASTPIN (-5925 5600) $PN DG28
J 2
(-5935 5610);
DISPLAY 0.489362 (-5935 5610);
PAINT MONO (-5935 5610);
FORCEPROP 0 LASTPIN (-5925 5550) $PN DJ23
J 2
(-5935 5560);
DISPLAY 0.489362 (-5935 5560);
PAINT MONO (-5935 5560);
FORCEPROP 0 LASTPIN (-5925 5450) $PN DJ26
J 2
(-5935 5460);
DISPLAY 0.489362 (-5935 5460);
PAINT MONO (-5935 5460);
FORCEPROP 0 LASTPIN (-5925 4350) $PN DE27
J 2
(-5935 4360);
DISPLAY 0.489362 (-5935 4360);
PAINT MONO (-5935 4360);
FORCEPROP 0 LASTPIN (-5925 5900) $PN DF30
J 2
(-5935 5910);
DISPLAY 0.489362 (-5935 5910);
PAINT MONO (-5935 5910);
FORCEPROP 0 LASTPIN (-5925 5850) $PN DG26
J 2
(-5935 5860);
DISPLAY 0.489362 (-5935 5860);
PAINT MONO (-5935 5860);
FORCEPROP 0 LASTPIN (-5925 5800) $PN DH27
J 2
(-5935 5810);
DISPLAY 0.489362 (-5935 5810);
PAINT MONO (-5935 5810);
FORCEPROP 0 LASTPIN (-3425 5850) $PN A25
J 0
(-3415 5860);
DISPLAY 0.489362 (-3415 5860);
PAINT MONO (-3415 5860);
FORCEPROP 0 LASTPIN (-3425 5900) $PN A26
J 0
(-3415 5910);
DISPLAY 0.489362 (-3415 5910);
PAINT MONO (-3415 5910);
FORCEPROP 0 LASTPIN (-3425 3950) $PN E23
J 0
(-3415 3960);
DISPLAY 0.489362 (-3415 3960);
PAINT MONO (-3415 3960);
FORCEPROP 0 LASTPIN (-3425 5200) $PN E26
J 0
(-3415 5210);
DISPLAY 0.489362 (-3415 5210);
PAINT MONO (-3415 5210);
FORCEPROP 0 LASTPIN (-3425 5250) $PN E27
J 0
(-3415 5260);
DISPLAY 0.489362 (-3415 5260);
PAINT MONO (-3415 5260);
FORCEPROP 0 LASTPIN (-3425 4550) $PN C26
J 0
(-3415 4560);
DISPLAY 0.489362 (-3415 4560);
PAINT MONO (-3415 4560);
FORCEPROP 0 LASTPIN (-3425 4600) $PN C25
J 0
(-3415 4610);
DISPLAY 0.489362 (-3415 4610);
PAINT MONO (-3415 4610);
FORCEPROP 0 LASTPIN (-3425 5700) $PN A29
J 0
(-3415 5710);
DISPLAY 0.489362 (-3415 5710);
PAINT MONO (-3415 5710);
FORCEPROP 0 LASTPIN (-3425 5750) $PN A28
J 0
(-3415 5760);
DISPLAY 0.489362 (-3415 5760);
PAINT MONO (-3415 5760);
FORCEPROP 0 LASTPIN (-3425 3900) $PN E24
J 0
(-3415 3910);
DISPLAY 0.489362 (-3415 3910);
PAINT MONO (-3415 3910);
FORCEPROP 0 LASTPIN (-3425 5050) $PN C28
J 0
(-3415 5060);
DISPLAY 0.489362 (-3415 5060);
PAINT MONO (-3415 5060);
FORCEPROP 0 LASTPIN (-3425 5100) $PN C29
J 0
(-3415 5110);
DISPLAY 0.489362 (-3415 5110);
PAINT MONO (-3415 5110);
FORCEPROP 0 LASTPIN (-3425 4400) $PN E29
J 0
(-3415 4410);
DISPLAY 0.489362 (-3415 4410);
PAINT MONO (-3415 4410);
FORCEPROP 0 LASTPIN (-3425 4450) $PN E30
J 0
(-3415 4460);
DISPLAY 0.489362 (-3415 4460);
PAINT MONO (-3415 4460);
FORCEPROP 0 LASTPIN (-3425 5550) $PN DH67
J 0
(-3415 5560);
DISPLAY 0.489362 (-3415 5560);
PAINT MONO (-3415 5560);
FORCEPROP 0 LASTPIN (-3425 5600) $PN DJ67
J 0
(-3415 5610);
DISPLAY 0.489362 (-3415 5610);
PAINT MONO (-3415 5610);
FORCEPROP 0 LASTPIN (-3425 3850) $PN DG40
J 0
(-3415 3860);
DISPLAY 0.489362 (-3415 3860);
PAINT MONO (-3415 3860);
FORCEPROP 0 LASTPIN (-3425 4900) $PN DH65
J 0
(-3415 4910);
DISPLAY 0.489362 (-3415 4910);
PAINT MONO (-3415 4910);
FORCEPROP 0 LASTPIN (-3425 4950) $PN DJ65
J 0
(-3415 4960);
DISPLAY 0.489362 (-3415 4960);
PAINT MONO (-3415 4960);
FORCEPROP 0 LASTPIN (-3425 4250) $PN DJ69
J 0
(-3415 4260);
DISPLAY 0.489362 (-3415 4260);
PAINT MONO (-3415 4260);
FORCEPROP 0 LASTPIN (-3425 4300) $PN DH69
J 0
(-3415 4310);
DISPLAY 0.489362 (-3415 4310);
PAINT MONO (-3415 4310);
FORCEPROP 0 LASTPIN (-3425 5400) $PN DJ60
J 0
(-3415 5410);
DISPLAY 0.489362 (-3415 5410);
PAINT MONO (-3415 5410);
FORCEPROP 0 LASTPIN (-3425 5450) $PN DH60
J 0
(-3415 5460);
DISPLAY 0.489362 (-3415 5460);
PAINT MONO (-3415 5460);
FORCEPROP 0 LASTPIN (-3425 3800) $PN DH40
J 0
(-3415 3810);
DISPLAY 0.489362 (-3415 3810);
PAINT MONO (-3415 3810);
FORCEPROP 0 LASTPIN (-3425 4750) $PN DH62
J 0
(-3415 4760);
DISPLAY 0.489362 (-3415 4760);
PAINT MONO (-3415 4760);
FORCEPROP 0 LASTPIN (-3425 4800) $PN DJ62
J 0
(-3415 4810);
DISPLAY 0.489362 (-3415 4810);
PAINT MONO (-3415 4810);
FORCEPROP 0 LASTPIN (-3425 4100) $PN DH58
J 0
(-3415 4110);
DISPLAY 0.489362 (-3415 4110);
PAINT MONO (-3415 4110);
FORCEPROP 0 LASTPIN (-3425 4150) $PN DG58
J 0
(-3415 4160);
DISPLAY 0.489362 (-3415 4160);
PAINT MONO (-3415 4160);
FORCEPROP 1 LAST PART_NUMBER DGA^6000030
J 0
(-5775 6150);
DISPLAY 0.489362 (-5775 6150);
PAINT SKYBLUE (-5775 6150);
FORCEPROP 2 LAST VALUE SOCKET6096_13568-001
J 0
(-5775 6228);
DISPLAY 0.489362 (-5775 6228);
PAINT SKYBLUE (-5775 6228);
FORCEPROP 1 LAST MATERIAL IO
J 0
(-5770 6082);
DISPLAY 0.489362 (-5770 6082);
PAINT SKYBLUE (-5770 6082);
FORCEPROP 2 LAST PART_TYPE SMLF
J 0
(-5775 6275);
DISPLAY 1.021277 (-5775 6275);
FORCEPROP 1 LAST PATH I287
J 0
(-4675 4825);
DISPLAY 0.723404 (-4675 4825);
PAINT GREEN (-4675 4825);
DISPLAY INVISIBLE (-4675 4825);
FORCEPROP 2 LAST CDS_LIB pure_quanta
J 0
(-4675 4825);
DISPLAY INVISIBLE (-4675 4825);
FORCEPROP 1 LAST CDS_LMAN_SYM_OUTLINE -1100,1225,1100,-1225
J 0
(-4675 4825);
DISPLAY 0.468085 (-4675 4825);
PAINT GREEN (-4675 4825);
DISPLAY INVISIBLE (-4675 4825);
FORCEPROP 1 LAST NEEDS_NO_SIZE TRUE
J 0
(-4675 4825);
DISPLAY 0.723404 (-4675 4825);
PAINT GREEN (-4675 4825);
DISPLAY INVISIBLE (-4675 4825);
FORCEADD Q_RES..1
(-6950 4850);
FORCEPROP 1 LAST LOCATION R470
J 0
(-6825 4850);
DISPLAY 0.489362 (-6825 4850);
PAINT SKYBLUE (-6825 4850);
FORCEPROP 0 LAST $SEC 1
J 0
(-6825 4875);
DISPLAY 0.680851 (-6825 4875);
PAINT MONO (-6825 4875);
DISPLAY INVISIBLE (-6825 4875);
FORCEPROP 0 LAST CDS_SEC 1
J 0
(-6825 4875);
DISPLAY 1.021277 (-6825 4875);
DISPLAY INVISIBLE (-6825 4875);
FORCEPROP 1 LASTPIN (-7050 4850) $PN 1
J 0
(-7038 4862);
DISPLAY 0.489362 (-7038 4862);
PAINT MONO (-7038 4862);
FORCEPROP 1 LASTPIN (-6850 4850) $PN 2
J 0
(-6888 4862);
DISPLAY 0.489362 (-6888 4862);
PAINT MONO (-6888 4862);
FORCEPROP 1 LAST VALUE 33
J 2
(-7050 4850);
DISPLAY 0.489362 (-7050 4850);
PAINT SKYBLUE (-7050 4850);
FORCEPROP 1 LAST PACK_TYPE 0402LF
J 0
(-6900 4775);
DISPLAY 0.489362 (-6900 4775);
PAINT SKYBLUE (-6900 4775);
DISPLAY INVISIBLE (-6900 4775);
FORCEPROP 1 LAST PART_NUMBER CS03302JB29
J 0
(-6925 4900);
DISPLAY 0.489362 (-6925 4900);
PAINT SKYBLUE (-6925 4900);
DISPLAY INVISIBLE (-6925 4900);
FORCEPROP 1 LAST TOLERANCE 5%
J 0
(-6975 4775);
DISPLAY 0.489362 (-6975 4775);
PAINT SKYBLUE (-6975 4775);
DISPLAY INVISIBLE (-6975 4775);
FORCEPROP 1 LAST MATERIAL CHIP
J 0
(-6525 4775);
DISPLAY 0.489362 (-6525 4775);
PAINT SKYBLUE (-6525 4775);
DISPLAY INVISIBLE (-6525 4775);
FORCEPROP 1 LAST WATTAGE 1/16W
J 2
(-6550 4775);
DISPLAY 0.489362 (-6550 4775);
PAINT SKYBLUE (-6550 4775);
DISPLAY INVISIBLE (-6550 4775);
FORCEPROP 1 LAST PATH I327
J 0
(-7000 5000);
DISPLAY 0.978723 (-7000 5000);
PAINT WHITE (-7000 5000);
DISPLAY INVISIBLE (-7000 5000);
FORCEPROP 2 LAST CDS_LIB pure_quanta
J 0
(-6950 4850);
DISPLAY INVISIBLE (-6950 4850);
FORCEADD Q_RES..1
(-6950 4900);
FORCEPROP 1 LAST LOCATION R469
J 0
(-6825 4900);
DISPLAY 0.489362 (-6825 4900);
PAINT SKYBLUE (-6825 4900);
FORCEPROP 0 LAST $SEC 1
J 0
(-6825 4925);
DISPLAY 0.680851 (-6825 4925);
PAINT MONO (-6825 4925);
DISPLAY INVISIBLE (-6825 4925);
FORCEPROP 0 LAST CDS_SEC 1
J 0
(-6825 4925);
DISPLAY 1.021277 (-6825 4925);
DISPLAY INVISIBLE (-6825 4925);
FORCEPROP 1 LASTPIN (-7050 4900) $PN 1
J 0
(-7038 4912);
DISPLAY 0.489362 (-7038 4912);
PAINT MONO (-7038 4912);
FORCEPROP 1 LASTPIN (-6850 4900) $PN 2
J 0
(-6888 4912);
DISPLAY 0.489362 (-6888 4912);
PAINT MONO (-6888 4912);
FORCEPROP 1 LAST VALUE 33
J 2
(-7050 4900);
DISPLAY 0.489362 (-7050 4900);
PAINT SKYBLUE (-7050 4900);
FORCEPROP 1 LAST PACK_TYPE 0402LF
J 0
(-6900 4825);
DISPLAY 0.489362 (-6900 4825);
PAINT SKYBLUE (-6900 4825);
DISPLAY INVISIBLE (-6900 4825);
FORCEPROP 1 LAST PART_NUMBER CS03302JB29
J 0
(-6925 4950);
DISPLAY 0.489362 (-6925 4950);
PAINT SKYBLUE (-6925 4950);
DISPLAY INVISIBLE (-6925 4950);
FORCEPROP 1 LAST TOLERANCE 5%
J 0
(-6975 4825);
DISPLAY 0.489362 (-6975 4825);
PAINT SKYBLUE (-6975 4825);
DISPLAY INVISIBLE (-6975 4825);
FORCEPROP 1 LAST MATERIAL CHIP
J 0
(-6525 4825);
DISPLAY 0.489362 (-6525 4825);
PAINT SKYBLUE (-6525 4825);
DISPLAY INVISIBLE (-6525 4825);
FORCEPROP 1 LAST WATTAGE 1/16W
J 2
(-6550 4825);
DISPLAY 0.489362 (-6550 4825);
PAINT SKYBLUE (-6550 4825);
DISPLAY INVISIBLE (-6550 4825);
FORCEPROP 1 LAST PATH I328
J 0
(-7000 5050);
DISPLAY 0.978723 (-7000 5050);
PAINT WHITE (-7000 5050);
DISPLAY INVISIBLE (-7000 5050);
FORCEPROP 2 LAST CDS_LIB pure_quanta
J 0
(-6950 4900);
DISPLAY INVISIBLE (-6950 4900);
FORCEADD Q_RES..1
(-6950 4950);
FORCEPROP 1 LAST LOCATION R468
J 0
(-6825 4950);
DISPLAY 0.489362 (-6825 4950);
PAINT SKYBLUE (-6825 4950);
FORCEPROP 0 LAST $SEC 1
J 0
(-6825 4975);
DISPLAY 0.680851 (-6825 4975);
PAINT MONO (-6825 4975);
DISPLAY INVISIBLE (-6825 4975);
FORCEPROP 0 LAST CDS_SEC 1
J 0
(-6825 4975);
DISPLAY 1.021277 (-6825 4975);
DISPLAY INVISIBLE (-6825 4975);
FORCEPROP 1 LASTPIN (-7050 4950) $PN 1
J 0
(-7038 4962);
DISPLAY 0.489362 (-7038 4962);
PAINT MONO (-7038 4962);
FORCEPROP 1 LASTPIN (-6850 4950) $PN 2
J 0
(-6888 4962);
DISPLAY 0.489362 (-6888 4962);
PAINT MONO (-6888 4962);
FORCEPROP 1 LAST VALUE 33
J 2
(-7050 4950);
DISPLAY 0.489362 (-7050 4950);
PAINT SKYBLUE (-7050 4950);
FORCEPROP 1 LAST PACK_TYPE 0402LF
J 0
(-6900 4875);
DISPLAY 0.489362 (-6900 4875);
PAINT SKYBLUE (-6900 4875);
DISPLAY INVISIBLE (-6900 4875);
FORCEPROP 1 LAST PART_NUMBER CS03302JB29
J 0
(-6925 5000);
DISPLAY 0.489362 (-6925 5000);
PAINT SKYBLUE (-6925 5000);
DISPLAY INVISIBLE (-6925 5000);
FORCEPROP 1 LAST TOLERANCE 5%
J 0
(-6975 4875);
DISPLAY 0.489362 (-6975 4875);
PAINT SKYBLUE (-6975 4875);
DISPLAY INVISIBLE (-6975 4875);
FORCEPROP 1 LAST MATERIAL CHIP
J 0
(-6525 4875);
DISPLAY 0.489362 (-6525 4875);
PAINT SKYBLUE (-6525 4875);
DISPLAY INVISIBLE (-6525 4875);
FORCEPROP 1 LAST WATTAGE 1/16W
J 2
(-6550 4875);
DISPLAY 0.489362 (-6550 4875);
PAINT SKYBLUE (-6550 4875);
DISPLAY INVISIBLE (-6550 4875);
FORCEPROP 1 LAST PATH I329
J 0
(-7000 5100);
DISPLAY 0.978723 (-7000 5100);
PAINT WHITE (-7000 5100);
DISPLAY INVISIBLE (-7000 5100);
FORCEPROP 2 LAST CDS_LIB pure_quanta
J 0
(-6950 4950);
DISPLAY INVISIBLE (-6950 4950);
FORCEADD Q_RES..1
(-6950 4800);
FORCEPROP 1 LAST LOCATION R471
J 0
(-6825 4800);
DISPLAY 0.489362 (-6825 4800);
PAINT SKYBLUE (-6825 4800);
FORCEPROP 0 LAST $SEC 1
J 0
(-6825 4825);
DISPLAY 0.680851 (-6825 4825);
PAINT MONO (-6825 4825);
DISPLAY INVISIBLE (-6825 4825);
FORCEPROP 0 LAST CDS_SEC 1
J 0
(-6825 4825);
DISPLAY 1.021277 (-6825 4825);
DISPLAY INVISIBLE (-6825 4825);
FORCEPROP 1 LASTPIN (-7050 4800) $PN 1
J 0
(-7038 4812);
DISPLAY 0.489362 (-7038 4812);
PAINT MONO (-7038 4812);
FORCEPROP 1 LASTPIN (-6850 4800) $PN 2
J 0
(-6888 4812);
DISPLAY 0.489362 (-6888 4812);
PAINT MONO (-6888 4812);
FORCEPROP 1 LAST VALUE 33
J 2
(-7050 4800);
DISPLAY 0.489362 (-7050 4800);
PAINT SKYBLUE (-7050 4800);
FORCEPROP 1 LAST PACK_TYPE 0402LF
J 0
(-6900 4725);
DISPLAY 0.489362 (-6900 4725);
PAINT SKYBLUE (-6900 4725);
DISPLAY INVISIBLE (-6900 4725);
FORCEPROP 1 LAST PART_NUMBER CS03302JB29
J 0
(-6925 4850);
DISPLAY 0.489362 (-6925 4850);
PAINT SKYBLUE (-6925 4850);
DISPLAY INVISIBLE (-6925 4850);
FORCEPROP 1 LAST TOLERANCE 5%
J 0
(-6975 4725);
DISPLAY 0.489362 (-6975 4725);
PAINT SKYBLUE (-6975 4725);
DISPLAY INVISIBLE (-6975 4725);
FORCEPROP 1 LAST MATERIAL CHIP
J 0
(-6525 4725);
DISPLAY 0.489362 (-6525 4725);
PAINT SKYBLUE (-6525 4725);
DISPLAY INVISIBLE (-6525 4725);
FORCEPROP 1 LAST WATTAGE 1/16W
J 2
(-6550 4725);
DISPLAY 0.489362 (-6550 4725);
PAINT SKYBLUE (-6550 4725);
DISPLAY INVISIBLE (-6550 4725);
FORCEPROP 1 LAST PATH I330
J 0
(-7000 4950);
DISPLAY 0.978723 (-7000 4950);
PAINT WHITE (-7000 4950);
DISPLAY INVISIBLE (-7000 4950);
FORCEPROP 2 LAST CDS_LIB pure_quanta
J 0
(-6950 4800);
DISPLAY INVISIBLE (-6950 4800);
FORCEADD Q_RES..1
(-6950 4650);
FORCEPROP 1 LAST LOCATION R472
J 0
(-6825 4650);
DISPLAY 0.489362 (-6825 4650);
PAINT SKYBLUE (-6825 4650);
FORCEPROP 0 LAST $SEC 1
J 0
(-6825 4675);
DISPLAY 0.680851 (-6825 4675);
PAINT MONO (-6825 4675);
DISPLAY INVISIBLE (-6825 4675);
FORCEPROP 0 LAST CDS_SEC 1
J 0
(-6825 4675);
DISPLAY 1.021277 (-6825 4675);
DISPLAY INVISIBLE (-6825 4675);
FORCEPROP 1 LASTPIN (-7050 4650) $PN 1
J 0
(-7038 4662);
DISPLAY 0.489362 (-7038 4662);
PAINT MONO (-7038 4662);
FORCEPROP 1 LASTPIN (-6850 4650) $PN 2
J 0
(-6888 4662);
DISPLAY 0.489362 (-6888 4662);
PAINT MONO (-6888 4662);
FORCEPROP 1 LAST VALUE 33
J 2
(-7050 4650);
DISPLAY 0.489362 (-7050 4650);
PAINT SKYBLUE (-7050 4650);
FORCEPROP 1 LAST PACK_TYPE 0402LF
J 0
(-6900 4575);
DISPLAY 0.489362 (-6900 4575);
PAINT SKYBLUE (-6900 4575);
DISPLAY INVISIBLE (-6900 4575);
FORCEPROP 1 LAST PART_NUMBER CS03302JB29
J 0
(-6925 4700);
DISPLAY 0.489362 (-6925 4700);
PAINT SKYBLUE (-6925 4700);
DISPLAY INVISIBLE (-6925 4700);
FORCEPROP 1 LAST TOLERANCE 5%
J 0
(-6975 4575);
DISPLAY 0.489362 (-6975 4575);
PAINT SKYBLUE (-6975 4575);
DISPLAY INVISIBLE (-6975 4575);
FORCEPROP 1 LAST MATERIAL CHIP
J 0
(-6525 4575);
DISPLAY 0.489362 (-6525 4575);
PAINT SKYBLUE (-6525 4575);
DISPLAY INVISIBLE (-6525 4575);
FORCEPROP 1 LAST WATTAGE 1/16W
J 2
(-6550 4575);
DISPLAY 0.489362 (-6550 4575);
PAINT SKYBLUE (-6550 4575);
DISPLAY INVISIBLE (-6550 4575);
FORCEPROP 1 LAST PATH I331
J 0
(-7000 4800);
DISPLAY 0.978723 (-7000 4800);
PAINT WHITE (-7000 4800);
DISPLAY INVISIBLE (-7000 4800);
FORCEPROP 2 LAST CDS_LIB pure_quanta
J 0
(-6950 4650);
DISPLAY INVISIBLE (-6950 4650);
FORCEADD Q_RES..1
(-6950 4350);
FORCEPROP 1 LAST LOCATION R474
J 0
(-6825 4350);
DISPLAY 0.489362 (-6825 4350);
PAINT SKYBLUE (-6825 4350);
FORCEPROP 0 LAST $SEC 1
J 0
(-6825 4375);
DISPLAY 0.680851 (-6825 4375);
PAINT MONO (-6825 4375);
DISPLAY INVISIBLE (-6825 4375);
FORCEPROP 0 LAST CDS_SEC 1
J 0
(-6825 4375);
DISPLAY 1.021277 (-6825 4375);
DISPLAY INVISIBLE (-6825 4375);
FORCEPROP 1 LASTPIN (-7050 4350) $PN 1
J 0
(-7038 4362);
DISPLAY 0.489362 (-7038 4362);
PAINT MONO (-7038 4362);
FORCEPROP 1 LASTPIN (-6850 4350) $PN 2
J 0
(-6888 4362);
DISPLAY 0.489362 (-6888 4362);
PAINT MONO (-6888 4362);
FORCEPROP 1 LAST VALUE 0
J 2
(-7050 4350);
DISPLAY 0.489362 (-7050 4350);
PAINT SKYBLUE (-7050 4350);
FORCEPROP 1 LAST PACK_TYPE 0402LF
J 0
(-6900 4275);
DISPLAY 0.489362 (-6900 4275);
PAINT SKYBLUE (-6900 4275);
DISPLAY INVISIBLE (-6900 4275);
FORCEPROP 1 LAST PART_NUMBER CS00002JB38
J 0
(-6925 4400);
DISPLAY 0.489362 (-6925 4400);
PAINT SKYBLUE (-6925 4400);
DISPLAY INVISIBLE (-6925 4400);
FORCEPROP 1 LAST TOLERANCE 5%
J 0
(-6975 4275);
DISPLAY 0.489362 (-6975 4275);
PAINT SKYBLUE (-6975 4275);
DISPLAY INVISIBLE (-6975 4275);
FORCEPROP 1 LAST MATERIAL CHIP
J 0
(-6525 4275);
DISPLAY 0.489362 (-6525 4275);
PAINT SKYBLUE (-6525 4275);
DISPLAY INVISIBLE (-6525 4275);
FORCEPROP 1 LAST WATTAGE 1/16W
J 2
(-6550 4275);
DISPLAY 0.489362 (-6550 4275);
PAINT SKYBLUE (-6550 4275);
DISPLAY INVISIBLE (-6550 4275);
FORCEPROP 1 LAST PATH I332
J 0
(-7000 4500);
DISPLAY 0.978723 (-7000 4500);
PAINT WHITE (-7000 4500);
DISPLAY INVISIBLE (-7000 4500);
FORCEPROP 2 LAST CDS_LIB pure_quanta
J 0
(-6950 4350);
DISPLAY INVISIBLE (-6950 4350);
FORCEADD OFFPAGE..2
R 2
(-7775 5900);
FORCEPROP 2 LAST $XR0 76 
J 0
(-7999 5900);
DISPLAY 0.638298 (-7999 5900);
PAINT MONO (-7999 5900);
FORCEPROP 2 LAST CDS_LIB standard
J 0
(-7775 5900);
DISPLAY INVISIBLE (-7775 5900);
FORCEPROP 1 LAST OFFPAGE TRUE
J 2
(-8100 5775);
DISPLAY 0.872340 (-8100 5775);
PAINT GREEN (-8100 5775);
DISPLAY INVISIBLE (-8100 5775);
FORCEPROP 1 LAST COMMENT_BODY TRUE
J 2
(-7730 5805);
DISPLAY 0.872340 (-7730 5805);
PAINT PEACH (-7730 5805);
DISPLAY INVISIBLE (-7730 5805);
FORCEPROP 2 LAST PATH I335
J 0
(-8025 5950);
DISPLAY 1.021277 (-8025 5950);
DISPLAY INVISIBLE (-8025 5950);
FORCEADD OFFPAGE..2
R 2
(-7775 5850);
FORCEPROP 2 LAST $XR0 76 
J 0
(-7999 5850);
DISPLAY 0.638298 (-7999 5850);
PAINT MONO (-7999 5850);
FORCEPROP 2 LAST CDS_LIB standard
J 0
(-7775 5850);
DISPLAY INVISIBLE (-7775 5850);
FORCEPROP 1 LAST OFFPAGE TRUE
J 2
(-8100 5725);
DISPLAY 0.872340 (-8100 5725);
PAINT GREEN (-8100 5725);
DISPLAY INVISIBLE (-8100 5725);
FORCEPROP 1 LAST COMMENT_BODY TRUE
J 2
(-7730 5755);
DISPLAY 0.872340 (-7730 5755);
PAINT PEACH (-7730 5755);
DISPLAY INVISIBLE (-7730 5755);
FORCEPROP 2 LAST PATH I336
J 0
(-8025 5900);
DISPLAY 1.021277 (-8025 5900);
DISPLAY INVISIBLE (-8025 5900);
FORCEADD OFFPAGE..2
R 2
(-7775 5650);
FORCEPROP 2 LAST $XR1 76 
J 0
(-8120 5650);
DISPLAY 0.638298 (-8120 5650);
PAINT MONO (-8120 5650);
FORCEPROP 2 LAST $XR0 144 
J 0
(-8030 5650);
DISPLAY 0.638298 (-8030 5650);
PAINT MONO (-8030 5650);
FORCEPROP 1 LAST COMMENT_BODY TRUE
J 2
(-7730 5555);
DISPLAY 0.872340 (-7730 5555);
PAINT PEACH (-7730 5555);
DISPLAY INVISIBLE (-7730 5555);
FORCEPROP 1 LAST OFFPAGE TRUE
J 2
(-8100 5525);
DISPLAY 0.872340 (-8100 5525);
PAINT GREEN (-8100 5525);
DISPLAY INVISIBLE (-8100 5525);
FORCEPROP 2 LAST CDS_LIB standard
J 2
(-7775 5650);
DISPLAY INVISIBLE (-7775 5650);
FORCEPROP 2 LAST PATH I337
J 0
(-8025 5700);
DISPLAY 1.021277 (-8025 5700);
DISPLAY INVISIBLE (-8025 5700);
FORCEADD OFFPAGE..1
(-7775 5450);
FORCEPROP 2 LAST $XR1 82 
J 0
(-8116 5450);
DISPLAY 0.638298 (-8116 5450);
PAINT MONO (-8116 5450);
FORCEPROP 2 LAST $XR0 80 
J 0
(-8026 5450);
DISPLAY 0.638298 (-8026 5450);
PAINT MONO (-8026 5450);
FORCEPROP 2 LAST CDS_LIB standard
J 0
(-7775 5450);
DISPLAY INVISIBLE (-7775 5450);
FORCEPROP 1 LAST OFFPAGE TRUE
J 0
(-7450 5325);
DISPLAY 0.872340 (-7450 5325);
PAINT GREEN (-7450 5325);
DISPLAY INVISIBLE (-7450 5325);
FORCEPROP 1 LAST COMMENT_BODY TRUE
J 0
(-7650 5350);
DISPLAY 0.872340 (-7650 5350);
PAINT GREEN (-7650 5350);
DISPLAY INVISIBLE (-7650 5350);
FORCEPROP 2 LAST PATH I339
J 0
(-8025 5500);
DISPLAY 1.021277 (-8025 5500);
DISPLAY INVISIBLE (-8025 5500);
FORCEADD OFFPAGE..3
R 2
(-7775 5250);
FORCEPROP 2 LAST $XR0 76 
J 0
(-8024 5250);
DISPLAY 0.638298 (-8024 5250);
PAINT MONO (-8024 5250);
FORCEPROP 2 LAST CDS_LIB standard
J 2
(-7775 5250);
DISPLAY INVISIBLE (-7775 5250);
FORCEPROP 1 LAST OFFPAGE TRUE
J 2
(-8100 5125);
DISPLAY 0.872340 (-8100 5125);
PAINT GREEN (-8100 5125);
DISPLAY INVISIBLE (-8100 5125);
FORCEPROP 1 LAST COMMENT_BODY TRUE
J 2
(-7725 5150);
DISPLAY 0.872340 (-7725 5150);
PAINT PEACH (-7725 5150);
DISPLAY INVISIBLE (-7725 5150);
FORCEPROP 2 LAST PATH I340
J 0
(-8050 5300);
DISPLAY 1.021277 (-8050 5300);
DISPLAY INVISIBLE (-8050 5300);
FORCEADD OFFPAGE..3
R 2
(-7775 5200);
FORCEPROP 2 LAST $XR0 76 
J 0
(-8024 5200);
DISPLAY 0.638298 (-8024 5200);
PAINT MONO (-8024 5200);
FORCEPROP 2 LAST CDS_LIB standard
J 2
(-7775 5200);
DISPLAY INVISIBLE (-7775 5200);
FORCEPROP 1 LAST OFFPAGE TRUE
J 2
(-8100 5075);
DISPLAY 0.872340 (-8100 5075);
PAINT GREEN (-8100 5075);
DISPLAY INVISIBLE (-8100 5075);
FORCEPROP 1 LAST COMMENT_BODY TRUE
J 2
(-7725 5100);
DISPLAY 0.872340 (-7725 5100);
PAINT PEACH (-7725 5100);
DISPLAY INVISIBLE (-7725 5100);
FORCEPROP 2 LAST PATH I341
J 0
(-8050 5250);
DISPLAY 1.021277 (-8050 5250);
DISPLAY INVISIBLE (-8050 5250);
FORCEADD OFFPAGE..3
R 2
(-7775 5100);
FORCEPROP 2 LAST $XR0 76 
J 0
(-8024 5100);
DISPLAY 0.638298 (-8024 5100);
PAINT MONO (-8024 5100);
FORCEPROP 2 LAST CDS_LIB standard
J 0
(-7775 5100);
DISPLAY INVISIBLE (-7775 5100);
FORCEPROP 1 LAST OFFPAGE TRUE
J 2
(-8100 4975);
DISPLAY 0.872340 (-8100 4975);
PAINT GREEN (-8100 4975);
DISPLAY INVISIBLE (-8100 4975);
FORCEPROP 1 LAST COMMENT_BODY TRUE
J 2
(-7725 5000);
DISPLAY 0.872340 (-7725 5000);
PAINT PEACH (-7725 5000);
DISPLAY INVISIBLE (-7725 5000);
FORCEPROP 2 LAST PATH I342
J 0
(-8050 5150);
DISPLAY 1.021277 (-8050 5150);
DISPLAY INVISIBLE (-8050 5150);
FORCEADD OFFPAGE..3
R 2
(-7775 5150);
FORCEPROP 2 LAST $XR0 76 
J 0
(-8024 5150);
DISPLAY 0.638298 (-8024 5150);
PAINT MONO (-8024 5150);
FORCEPROP 2 LAST CDS_LIB standard
J 0
(-7775 5150);
DISPLAY INVISIBLE (-7775 5150);
FORCEPROP 1 LAST OFFPAGE TRUE
J 2
(-8100 5025);
DISPLAY 0.872340 (-8100 5025);
PAINT GREEN (-8100 5025);
DISPLAY INVISIBLE (-8100 5025);
FORCEPROP 1 LAST COMMENT_BODY TRUE
J 2
(-7725 5050);
DISPLAY 0.872340 (-7725 5050);
PAINT PEACH (-7725 5050);
DISPLAY INVISIBLE (-7725 5050);
FORCEPROP 2 LAST PATH I343
J 0
(-8050 5200);
DISPLAY 1.021277 (-8050 5200);
DISPLAY INVISIBLE (-8050 5200);
FORCEADD OFFPAGE..1
(-7775 4650);
FORCEPROP 2 LAST $XR2 80 
J 0
(-8236 4650);
DISPLAY 0.638298 (-8236 4650);
PAINT MONO (-8236 4650);
FORCEPROP 2 LAST $XR1 117 
J 0
(-8146 4650);
DISPLAY 0.638298 (-8146 4650);
PAINT MONO (-8146 4650);
FORCEPROP 2 LAST $XR0 29 
J 0
(-8026 4650);
DISPLAY 0.638298 (-8026 4650);
PAINT MONO (-8026 4650);
FORCEPROP 2 LAST CDS_LIB standard
J 0
(-7775 4650);
DISPLAY INVISIBLE (-7775 4650);
FORCEPROP 1 LAST OFFPAGE TRUE
J 0
(-7450 4525);
DISPLAY 0.872340 (-7450 4525);
PAINT GREEN (-7450 4525);
DISPLAY INVISIBLE (-7450 4525);
FORCEPROP 1 LAST COMMENT_BODY TRUE
J 0
(-7650 4550);
DISPLAY 0.872340 (-7650 4550);
PAINT GREEN (-7650 4550);
DISPLAY INVISIBLE (-7650 4550);
FORCEPROP 2 LAST PATH I344
J 0
(-8025 4700);
DISPLAY 1.021277 (-8025 4700);
DISPLAY INVISIBLE (-8025 4700);
FORCEADD OFFPAGE..3
R 2
(-7775 4950);
FORCEPROP 2 LAST $XR2 117 
J 0
(-8234 4950);
DISPLAY 0.638298 (-8234 4950);
PAINT MONO (-8234 4950);
FORCEPROP 2 LAST $XR1 80 
J 0
(-8114 4950);
DISPLAY 0.638298 (-8114 4950);
PAINT MONO (-8114 4950);
FORCEPROP 2 LAST $XR0 29 
J 0
(-8024 4950);
DISPLAY 0.638298 (-8024 4950);
PAINT MONO (-8024 4950);
FORCEPROP 2 LAST CDS_LIB standard
J 2
(-7775 4950);
DISPLAY INVISIBLE (-7775 4950);
FORCEPROP 1 LAST OFFPAGE TRUE
J 2
(-8100 4825);
DISPLAY 0.872340 (-8100 4825);
PAINT GREEN (-8100 4825);
DISPLAY INVISIBLE (-8100 4825);
FORCEPROP 1 LAST COMMENT_BODY TRUE
J 2
(-7725 4850);
DISPLAY 0.872340 (-7725 4850);
PAINT PEACH (-7725 4850);
DISPLAY INVISIBLE (-7725 4850);
FORCEPROP 2 LAST PATH I345
J 0
(-8050 5000);
DISPLAY 1.021277 (-8050 5000);
DISPLAY INVISIBLE (-8050 5000);
FORCEADD OFFPAGE..3
R 2
(-7775 4850);
FORCEPROP 2 LAST $XR2 117 
J 0
(-8234 4850);
DISPLAY 0.638298 (-8234 4850);
PAINT MONO (-8234 4850);
FORCEPROP 2 LAST $XR1 80 
J 0
(-8114 4850);
DISPLAY 0.638298 (-8114 4850);
PAINT MONO (-8114 4850);
FORCEPROP 2 LAST $XR0 29 
J 0
(-8024 4850);
DISPLAY 0.638298 (-8024 4850);
PAINT MONO (-8024 4850);
FORCEPROP 2 LAST CDS_LIB standard
J 0
(-7775 4850);
DISPLAY INVISIBLE (-7775 4850);
FORCEPROP 1 LAST OFFPAGE TRUE
J 2
(-8100 4725);
DISPLAY 0.872340 (-8100 4725);
PAINT GREEN (-8100 4725);
DISPLAY INVISIBLE (-8100 4725);
FORCEPROP 1 LAST COMMENT_BODY TRUE
J 2
(-7725 4750);
DISPLAY 0.872340 (-7725 4750);
PAINT PEACH (-7725 4750);
DISPLAY INVISIBLE (-7725 4750);
FORCEPROP 2 LAST PATH I346
J 0
(-8050 4900);
DISPLAY 1.021277 (-8050 4900);
DISPLAY INVISIBLE (-8050 4900);
FORCEADD OFFPAGE..3
R 2
(-7775 4900);
FORCEPROP 2 LAST $XR2 117 
J 0
(-8234 4900);
DISPLAY 0.638298 (-8234 4900);
PAINT MONO (-8234 4900);
FORCEPROP 2 LAST $XR1 80 
J 0
(-8114 4900);
DISPLAY 0.638298 (-8114 4900);
PAINT MONO (-8114 4900);
FORCEPROP 2 LAST $XR0 29 
J 0
(-8024 4900);
DISPLAY 0.638298 (-8024 4900);
PAINT MONO (-8024 4900);
FORCEPROP 2 LAST CDS_LIB standard
J 2
(-7775 4900);
DISPLAY INVISIBLE (-7775 4900);
FORCEPROP 1 LAST OFFPAGE TRUE
J 2
(-8100 4775);
DISPLAY 0.872340 (-8100 4775);
PAINT GREEN (-8100 4775);
DISPLAY INVISIBLE (-8100 4775);
FORCEPROP 1 LAST COMMENT_BODY TRUE
J 2
(-7725 4800);
DISPLAY 0.872340 (-7725 4800);
PAINT PEACH (-7725 4800);
DISPLAY INVISIBLE (-7725 4800);
FORCEPROP 2 LAST PATH I347
J 0
(-8050 4950);
DISPLAY 1.021277 (-8050 4950);
DISPLAY INVISIBLE (-8050 4950);
FORCEADD OFFPAGE..3
R 2
(-7775 4800);
FORCEPROP 2 LAST $XR2 117 
J 0
(-8234 4800);
DISPLAY 0.638298 (-8234 4800);
PAINT MONO (-8234 4800);
FORCEPROP 2 LAST $XR1 80 
J 0
(-8114 4800);
DISPLAY 0.638298 (-8114 4800);
PAINT MONO (-8114 4800);
FORCEPROP 2 LAST $XR0 29 
J 0
(-8024 4800);
DISPLAY 0.638298 (-8024 4800);
PAINT MONO (-8024 4800);
FORCEPROP 2 LAST CDS_LIB standard
J 0
(-7775 4800);
DISPLAY INVISIBLE (-7775 4800);
FORCEPROP 1 LAST OFFPAGE TRUE
J 2
(-8100 4675);
DISPLAY 0.872340 (-8100 4675);
PAINT GREEN (-8100 4675);
DISPLAY INVISIBLE (-8100 4675);
FORCEPROP 1 LAST COMMENT_BODY TRUE
J 2
(-7725 4700);
DISPLAY 0.872340 (-7725 4700);
PAINT PEACH (-7725 4700);
DISPLAY INVISIBLE (-7725 4700);
FORCEPROP 2 LAST PATH I348
J 0
(-8050 4850);
DISPLAY 1.021277 (-8050 4850);
DISPLAY INVISIBLE (-8050 4850);
FORCEADD OFFPAGE..2
R 2
(-7775 4450);
FORCEPROP 2 LAST $XR2 117 
J 0
(-8209 4450);
DISPLAY 0.638298 (-8209 4450);
PAINT MONO (-8209 4450);
FORCEPROP 2 LAST $XR1 80 
J 0
(-8089 4450);
DISPLAY 0.638298 (-8089 4450);
PAINT MONO (-8089 4450);
FORCEPROP 2 LAST $XR0 75 
J 0
(-7999 4450);
DISPLAY 0.638298 (-7999 4450);
PAINT MONO (-7999 4450);
FORCEPROP 2 LAST CDS_LIB standard
J 0
(-7775 4450);
DISPLAY INVISIBLE (-7775 4450);
FORCEPROP 1 LAST OFFPAGE TRUE
J 2
(-8100 4325);
DISPLAY 0.872340 (-8100 4325);
PAINT GREEN (-8100 4325);
DISPLAY INVISIBLE (-8100 4325);
FORCEPROP 1 LAST COMMENT_BODY TRUE
J 2
(-7730 4355);
DISPLAY 0.872340 (-7730 4355);
PAINT PEACH (-7730 4355);
DISPLAY INVISIBLE (-7730 4355);
FORCEPROP 2 LAST PATH I349
J 0
(-8025 4500);
DISPLAY 1.021277 (-8025 4500);
DISPLAY INVISIBLE (-8025 4500);
FORCEADD OFFPAGE..1
(-7775 4400);
FORCEPROP 2 LAST $XR0 75 
J 0
(-8026 4400);
DISPLAY 0.638298 (-8026 4400);
PAINT MONO (-8026 4400);
FORCEPROP 2 LAST CDS_LIB standard
J 0
(-7775 4400);
DISPLAY INVISIBLE (-7775 4400);
FORCEPROP 1 LAST OFFPAGE TRUE
J 0
(-7450 4275);
DISPLAY 0.872340 (-7450 4275);
PAINT GREEN (-7450 4275);
DISPLAY INVISIBLE (-7450 4275);
FORCEPROP 1 LAST COMMENT_BODY TRUE
J 0
(-7650 4300);
DISPLAY 0.872340 (-7650 4300);
PAINT GREEN (-7650 4300);
DISPLAY INVISIBLE (-7650 4300);
FORCEPROP 2 LAST PATH I350
J 0
(-8050 4450);
DISPLAY 1.021277 (-8050 4450);
DISPLAY INVISIBLE (-8050 4450);
FORCEADD OFFPAGE..2
R 2
(-7775 4350);
FORCEPROP 2 LAST $XR2 117 
J 0
(-8209 4350);
DISPLAY 0.638298 (-8209 4350);
PAINT MONO (-8209 4350);
FORCEPROP 2 LAST $XR1 80 
J 0
(-8089 4350);
DISPLAY 0.638298 (-8089 4350);
PAINT MONO (-8089 4350);
FORCEPROP 2 LAST $XR0 29 
J 0
(-7999 4350);
DISPLAY 0.638298 (-7999 4350);
PAINT MONO (-7999 4350);
FORCEPROP 2 LAST CDS_LIB standard
J 0
(-7775 4350);
DISPLAY INVISIBLE (-7775 4350);
FORCEPROP 1 LAST OFFPAGE TRUE
J 2
(-8100 4225);
DISPLAY 0.872340 (-8100 4225);
PAINT GREEN (-8100 4225);
DISPLAY INVISIBLE (-8100 4225);
FORCEPROP 1 LAST COMMENT_BODY TRUE
J 2
(-7730 4255);
DISPLAY 0.872340 (-7730 4255);
PAINT PEACH (-7730 4255);
DISPLAY INVISIBLE (-7730 4255);
FORCEPROP 2 LAST PATH I351
J 0
(-7975 4400);
DISPLAY 1.021277 (-7975 4400);
DISPLAY INVISIBLE (-7975 4400);
FORCEADD OFFPAGE..2
R 2
(-7775 4250);
FORCEPROP 2 LAST $XR0 76 
J 0
(-7999 4250);
DISPLAY 0.638298 (-7999 4250);
PAINT MONO (-7999 4250);
FORCEPROP 2 LAST CDS_LIB standard
J 0
(-7775 4250);
DISPLAY INVISIBLE (-7775 4250);
FORCEPROP 1 LAST OFFPAGE TRUE
J 2
(-8100 4125);
DISPLAY 0.872340 (-8100 4125);
PAINT GREEN (-8100 4125);
DISPLAY INVISIBLE (-8100 4125);
FORCEPROP 1 LAST COMMENT_BODY TRUE
J 2
(-7730 4155);
DISPLAY 0.872340 (-7730 4155);
PAINT PEACH (-7730 4155);
DISPLAY INVISIBLE (-7730 4155);
FORCEPROP 2 LAST PATH I352
J 0
(-8025 4300);
DISPLAY 1.021277 (-8025 4300);
DISPLAY INVISIBLE (-8025 4300);
FORCEADD OFFPAGE..3
(-2475 5900);
FORCEPROP 2 LAST $XR0 146 
J 0
(-2261 5900);
DISPLAY 0.638298 (-2261 5900);
PAINT MONO (-2261 5900);
FORCEPROP 2 LAST CDS_LIB standard
J 0
(-2475 5900);
DISPLAY INVISIBLE (-2475 5900);
FORCEPROP 1 LAST OFFPAGE TRUE
J 0
(-2150 5775);
DISPLAY 0.872340 (-2150 5775);
PAINT GREEN (-2150 5775);
DISPLAY INVISIBLE (-2150 5775);
FORCEPROP 1 LAST COMMENT_BODY TRUE
J 0
(-2525 5800);
DISPLAY 0.872340 (-2525 5800);
PAINT GREEN (-2525 5800);
DISPLAY INVISIBLE (-2525 5800);
FORCEPROP 2 LAST PATH I353
J 0
(-2250 5950);
DISPLAY 1.021277 (-2250 5950);
DISPLAY INVISIBLE (-2250 5950);
FORCEADD OFFPAGE..3
(-2475 5850);
FORCEPROP 2 LAST $XR0 146 
J 0
(-2261 5850);
DISPLAY 0.638298 (-2261 5850);
PAINT MONO (-2261 5850);
FORCEPROP 2 LAST CDS_LIB standard
J 0
(-2475 5850);
DISPLAY INVISIBLE (-2475 5850);
FORCEPROP 1 LAST OFFPAGE TRUE
J 0
(-2150 5725);
DISPLAY 0.872340 (-2150 5725);
PAINT GREEN (-2150 5725);
DISPLAY INVISIBLE (-2150 5725);
FORCEPROP 1 LAST COMMENT_BODY TRUE
J 0
(-2525 5750);
DISPLAY 0.872340 (-2525 5750);
PAINT GREEN (-2525 5750);
DISPLAY INVISIBLE (-2525 5750);
FORCEPROP 2 LAST PATH I354
J 0
(-2250 5900);
DISPLAY 1.021277 (-2250 5900);
DISPLAY INVISIBLE (-2250 5900);
FORCEADD OFFPAGE..3
(-2475 5750);
FORCEPROP 2 LAST $XR0 117 
J 0
(-2261 5750);
DISPLAY 0.638298 (-2261 5750);
PAINT MONO (-2261 5750);
FORCEPROP 2 LAST CDS_LIB standard
J 0
(-2475 5750);
DISPLAY INVISIBLE (-2475 5750);
FORCEPROP 1 LAST OFFPAGE TRUE
J 0
(-2150 5625);
DISPLAY 0.872340 (-2150 5625);
PAINT GREEN (-2150 5625);
DISPLAY INVISIBLE (-2150 5625);
FORCEPROP 1 LAST COMMENT_BODY TRUE
J 0
(-2525 5650);
DISPLAY 0.872340 (-2525 5650);
PAINT GREEN (-2525 5650);
DISPLAY INVISIBLE (-2525 5650);
FORCEPROP 2 LAST PATH I355
J 0
(-2250 5800);
DISPLAY 1.021277 (-2250 5800);
DISPLAY INVISIBLE (-2250 5800);
FORCEADD OFFPAGE..3
(-2475 5700);
FORCEPROP 2 LAST $XR0 117 
J 0
(-2261 5700);
DISPLAY 0.638298 (-2261 5700);
PAINT MONO (-2261 5700);
FORCEPROP 2 LAST CDS_LIB standard
J 0
(-2475 5700);
DISPLAY INVISIBLE (-2475 5700);
FORCEPROP 1 LAST OFFPAGE TRUE
J 0
(-2150 5575);
DISPLAY 0.872340 (-2150 5575);
PAINT GREEN (-2150 5575);
DISPLAY INVISIBLE (-2150 5575);
FORCEPROP 1 LAST COMMENT_BODY TRUE
J 0
(-2525 5600);
DISPLAY 0.872340 (-2525 5600);
PAINT GREEN (-2525 5600);
DISPLAY INVISIBLE (-2525 5600);
FORCEPROP 2 LAST PATH I356
J 0
(-2250 5750);
DISPLAY 1.021277 (-2250 5750);
DISPLAY INVISIBLE (-2250 5750);
FORCEADD OFFPAGE..2
(-1225 4250);
FORCEPROP 2 LAST $XR0 145 
J 0
(-1036 4250);
DISPLAY 0.638298 (-1036 4250);
PAINT MONO (-1036 4250);
FORCEPROP 2 LAST CDS_LIB standard
J 0
(-1225 4250);
DISPLAY INVISIBLE (-1225 4250);
FORCEPROP 1 LAST OFFPAGE TRUE
J 0
(-900 4125);
DISPLAY 0.872340 (-900 4125);
PAINT GREEN (-900 4125);
DISPLAY INVISIBLE (-900 4125);
FORCEPROP 1 LAST COMMENT_BODY TRUE
J 0
(-1270 4155);
DISPLAY 0.872340 (-1270 4155);
PAINT GREEN (-1270 4155);
DISPLAY INVISIBLE (-1270 4155);
FORCEPROP 2 LAST PATH I363
J 0
(-1050 4325);
DISPLAY 1.021277 (-1050 4325);
DISPLAY INVISIBLE (-1050 4325);
FORCEADD OFFPAGE..2
(-1225 4300);
FORCEPROP 2 LAST $XR0 145 
J 0
(-1036 4300);
DISPLAY 0.638298 (-1036 4300);
PAINT MONO (-1036 4300);
FORCEPROP 2 LAST CDS_LIB standard
J 0
(-1225 4300);
DISPLAY INVISIBLE (-1225 4300);
FORCEPROP 1 LAST OFFPAGE TRUE
J 0
(-900 4175);
DISPLAY 0.872340 (-900 4175);
PAINT GREEN (-900 4175);
DISPLAY INVISIBLE (-900 4175);
FORCEPROP 1 LAST COMMENT_BODY TRUE
J 0
(-1270 4205);
DISPLAY 0.872340 (-1270 4205);
PAINT GREEN (-1270 4205);
DISPLAY INVISIBLE (-1270 4205);
FORCEPROP 2 LAST PATH I364
J 0
(-1050 4375);
DISPLAY 1.021277 (-1050 4375);
DISPLAY INVISIBLE (-1050 4375);
FORCEADD OFFPAGE..3
(-2475 5600);
FORCEPROP 2 LAST $XR0 145 
J 0
(-2261 5600);
DISPLAY 0.638298 (-2261 5600);
PAINT MONO (-2261 5600);
FORCEPROP 2 LAST CDS_LIB standard
J 0
(-2475 5600);
DISPLAY INVISIBLE (-2475 5600);
FORCEPROP 1 LAST OFFPAGE TRUE
J 0
(-2150 5475);
DISPLAY 0.872340 (-2150 5475);
PAINT GREEN (-2150 5475);
DISPLAY INVISIBLE (-2150 5475);
FORCEPROP 1 LAST COMMENT_BODY TRUE
J 0
(-2525 5500);
DISPLAY 0.872340 (-2525 5500);
PAINT GREEN (-2525 5500);
DISPLAY INVISIBLE (-2525 5500);
FORCEPROP 2 LAST PATH I365
J 0
(-2250 5650);
DISPLAY 1.021277 (-2250 5650);
DISPLAY INVISIBLE (-2250 5650);
FORCEADD OFFPAGE..3
(-2475 5550);
FORCEPROP 2 LAST $XR0 145 
J 0
(-2261 5550);
DISPLAY 0.638298 (-2261 5550);
PAINT MONO (-2261 5550);
FORCEPROP 2 LAST CDS_LIB standard
J 0
(-2475 5550);
DISPLAY INVISIBLE (-2475 5550);
FORCEPROP 1 LAST OFFPAGE TRUE
J 0
(-2150 5425);
DISPLAY 0.872340 (-2150 5425);
PAINT GREEN (-2150 5425);
DISPLAY INVISIBLE (-2150 5425);
FORCEPROP 1 LAST COMMENT_BODY TRUE
J 0
(-2525 5450);
DISPLAY 0.872340 (-2525 5450);
PAINT GREEN (-2525 5450);
DISPLAY INVISIBLE (-2525 5450);
FORCEPROP 2 LAST PATH I366
J 0
(-2250 5600);
DISPLAY 1.021277 (-2250 5600);
DISPLAY INVISIBLE (-2250 5600);
FORCEADD OFFPAGE..1
R 2
(-1225 3850);
FORCEPROP 2 LAST $XR0 145 
J 0
(-1039 3850);
DISPLAY 0.638298 (-1039 3850);
PAINT MONO (-1039 3850);
FORCEPROP 2 LAST CDS_LIB standard
J 0
(-1225 3850);
DISPLAY INVISIBLE (-1225 3850);
FORCEPROP 1 LAST OFFPAGE TRUE
J 2
(-1550 3725);
DISPLAY 0.872340 (-1550 3725);
PAINT GREEN (-1550 3725);
DISPLAY INVISIBLE (-1550 3725);
FORCEPROP 1 LAST COMMENT_BODY TRUE
J 2
(-1350 3750);
DISPLAY 0.872340 (-1350 3750);
PAINT GREEN (-1350 3750);
DISPLAY INVISIBLE (-1350 3750);
FORCEPROP 2 LAST PATH I367
J 0
(-1050 3925);
DISPLAY 1.021277 (-1050 3925);
DISPLAY INVISIBLE (-1050 3925);
FORCEADD OFFPAGE..1
R 2
(-1225 3950);
FORCEPROP 2 LAST $XR0 29 
J 0
(-1039 3950);
DISPLAY 0.638298 (-1039 3950);
PAINT MONO (-1039 3950);
FORCEPROP 2 LAST CDS_LIB standard
J 0
(-1225 3950);
DISPLAY INVISIBLE (-1225 3950);
FORCEPROP 1 LAST OFFPAGE TRUE
J 2
(-1550 3825);
DISPLAY 0.872340 (-1550 3825);
PAINT GREEN (-1550 3825);
DISPLAY INVISIBLE (-1550 3825);
FORCEPROP 1 LAST COMMENT_BODY TRUE
J 2
(-1350 3850);
DISPLAY 0.872340 (-1350 3850);
PAINT GREEN (-1350 3850);
DISPLAY INVISIBLE (-1350 3850);
FORCEPROP 2 LAST PATH I372
J 0
(-1050 4025);
DISPLAY 1.021277 (-1050 4025);
DISPLAY INVISIBLE (-1050 4025);
FORCEADD SN74LVC1G07DBVR..1
(-2625 2550);
FORCEPROP 1 LAST LOCATION U3
J 0
(-2750 2805);
DISPLAY 0.489362 (-2750 2805);
PAINT SKYBLUE (-2750 2805);
FORCEPROP 0 LAST $SEC 1
J 0
(-2750 2950);
DISPLAY 0.680851 (-2750 2950);
PAINT MONO (-2750 2950);
DISPLAY INVISIBLE (-2750 2950);
FORCEPROP 0 LAST CDS_SEC 1
J 0
(-2750 2950);
DISPLAY 1.021277 (-2750 2950);
DISPLAY INVISIBLE (-2750 2950);
FORCEPROP 0 LASTPIN (-2800 2550) $PN 2
J 2
(-2810 2560);
DISPLAY 0.489362 (-2810 2560);
PAINT MONO (-2810 2560);
FORCEPROP 0 LASTPIN (-2800 2450) $PN 3
J 2
(-2810 2460);
DISPLAY 0.489362 (-2810 2460);
PAINT MONO (-2810 2460);
FORCEPROP 0 LASTPIN (-2450 2450) $PN 1
J 0
(-2440 2460);
DISPLAY 0.489362 (-2440 2460);
PAINT MONO (-2440 2460);
FORCEPROP 0 LASTPIN (-2800 2650) $PN 5
J 2
(-2810 2660);
DISPLAY 0.489362 (-2810 2660);
PAINT MONO (-2810 2660);
FORCEPROP 0 LASTPIN (-2450 2550) $PN 4
J 0
(-2440 2560);
DISPLAY 0.489362 (-2440 2560);
PAINT MONO (-2440 2560);
FORCEPROP 2 LAST PACK_TYPE SMLF
J 0
(-2750 2850);
DISPLAY 0.489362 (-2750 2850);
PAINT SKYBLUE (-2750 2850);
FORCEPROP 2 LAST VALUE SN74LVC1G07DBVR
J 0
(-2750 2900);
DISPLAY 0.489362 (-2750 2900);
PAINT SKYBLUE (-2750 2900);
FORCEPROP 1 LAST MATERIAL IC
J 0
(-2750 2710);
DISPLAY 0.489362 (-2750 2710);
PAINT SKYBLUE (-2750 2710);
FORCEPROP 1 LAST PART_NUMBER AL1G0007024
J 0
(-2750 2760);
DISPLAY 0.489362 (-2750 2760);
PAINT SKYBLUE (-2750 2760);
FORCEPROP 1 LAST PATH I373
J 0
(-2525 2705);
DISPLAY 0.723404 (-2525 2705);
PAINT GREEN (-2525 2705);
DISPLAY INVISIBLE (-2525 2705);
FORCEPROP 2 LAST CDS_LIB pure_quanta
J 0
(-2625 2550);
DISPLAY INVISIBLE (-2625 2550);
FORCEPROP 1 LAST NEEDS_NO_SIZE TRUE
J 0
(-2625 2550);
DISPLAY 0.468085 (-2625 2550);
PAINT GREEN (-2625 2550);
DISPLAY INVISIBLE (-2625 2550);
FORCEADD OFFPAGE..1
(-3850 2550);
FORCEPROP 2 LAST $XR1 82 
J 0
(-4191 2550);
DISPLAY 0.638298 (-4191 2550);
PAINT MONO (-4191 2550);
FORCEPROP 2 LAST $XR0 80 
J 0
(-4101 2550);
DISPLAY 0.638298 (-4101 2550);
PAINT MONO (-4101 2550);
FORCEPROP 2 LAST CDS_LIB standard
J 0
(-3850 2550);
DISPLAY INVISIBLE (-3850 2550);
FORCEPROP 1 LAST OFFPAGE TRUE
J 0
(-3525 2425);
DISPLAY 0.872340 (-3525 2425);
PAINT GREEN (-3525 2425);
DISPLAY INVISIBLE (-3525 2425);
FORCEPROP 1 LAST COMMENT_BODY TRUE
J 0
(-3725 2450);
DISPLAY 0.872340 (-3725 2450);
PAINT GREEN (-3725 2450);
DISPLAY INVISIBLE (-3725 2450);
FORCEPROP 2 LAST PATH I376
J 0
(-3800 2625);
DISPLAY 1.021277 (-3800 2625);
DISPLAY INVISIBLE (-3800 2625);
FORCEADD Q_RES..1
(-1775 2550);
FORCEPROP 1 LAST LOCATION R589
J 0
(-1825 2600);
DISPLAY 0.489362 (-1825 2600);
PAINT SKYBLUE (-1825 2600);
FORCEPROP 0 LAST $SEC 1
J 0
(-1825 2650);
DISPLAY 0.680851 (-1825 2650);
PAINT MONO (-1825 2650);
DISPLAY INVISIBLE (-1825 2650);
FORCEPROP 0 LAST CDS_SEC 1
J 0
(-1825 2650);
DISPLAY 1.021277 (-1825 2650);
DISPLAY INVISIBLE (-1825 2650);
FORCEPROP 1 LASTPIN (-1875 2550) $PN 1
J 0
(-1863 2562);
DISPLAY 0.489362 (-1863 2562);
PAINT MONO (-1863 2562);
FORCEPROP 1 LASTPIN (-1675 2550) $PN 2
J 0
(-1713 2562);
DISPLAY 0.489362 (-1713 2562);
PAINT MONO (-1713 2562);
FORCEPROP 1 LAST VALUE 0
J 2
(-1875 2550);
DISPLAY 0.489362 (-1875 2550);
PAINT SKYBLUE (-1875 2550);
FORCEPROP 1 LAST PACK_TYPE 0402LF
J 0
(-1725 2475);
DISPLAY 0.489362 (-1725 2475);
PAINT SKYBLUE (-1725 2475);
DISPLAY INVISIBLE (-1725 2475);
FORCEPROP 1 LAST PART_NUMBER CS00002JB38
J 0
(-1750 2600);
DISPLAY 0.489362 (-1750 2600);
PAINT SKYBLUE (-1750 2600);
DISPLAY INVISIBLE (-1750 2600);
FORCEPROP 1 LAST TOLERANCE 5%
J 0
(-1800 2475);
DISPLAY 0.489362 (-1800 2475);
PAINT SKYBLUE (-1800 2475);
DISPLAY INVISIBLE (-1800 2475);
FORCEPROP 1 LAST MATERIAL CHIP
J 0
(-1350 2475);
DISPLAY 0.489362 (-1350 2475);
PAINT SKYBLUE (-1350 2475);
DISPLAY INVISIBLE (-1350 2475);
FORCEPROP 1 LAST WATTAGE 1/16W
J 2
(-1375 2475);
DISPLAY 0.489362 (-1375 2475);
PAINT SKYBLUE (-1375 2475);
DISPLAY INVISIBLE (-1375 2475);
FORCEPROP 1 LAST PATH I377
J 0
(-1825 2700);
DISPLAY 0.978723 (-1825 2700);
PAINT WHITE (-1825 2700);
DISPLAY INVISIBLE (-1825 2700);
FORCEPROP 2 LAST CDS_LIB pure_quanta
J 0
(-1775 2550);
DISPLAY INVISIBLE (-1775 2550);
FORCEADD Q_CAP..1
R 2
(-2975 2850);
FORCEPROP 1 LAST LOCATION C30
J 2
(-3025 2975);
DISPLAY 0.489362 (-3025 2975);
PAINT SKYBLUE (-3025 2975);
FORCEPROP 0 LAST $SEC 1
J 0
(-3025 3025);
DISPLAY 0.680851 (-3025 3025);
PAINT MONO (-3025 3025);
DISPLAY INVISIBLE (-3025 3025);
FORCEPROP 0 LAST CDS_SEC 1
J 0
(-3025 3025);
DISPLAY 1.021277 (-3025 3025);
DISPLAY INVISIBLE (-3025 3025);
FORCEPROP 1 LASTPIN (-2975 2950) $PN 1
J 2
(-2985 2930);
DISPLAY 0.489362 (-2985 2930);
PAINT MONO (-2985 2930);
FORCEPROP 1 LASTPIN (-2975 2750) $PN 2
J 2
(-2985 2730);
DISPLAY 0.489362 (-2985 2730);
PAINT MONO (-2985 2730);
FORCEPROP 1 LAST PACK_TYPE 0402
J 2
(-3025 2750);
DISPLAY 0.489362 (-3025 2750);
PAINT SKYBLUE (-3025 2750);
FORCEPROP 1 LAST VOLTAGE 25V
J 2
(-3025 2900);
DISPLAY 0.489362 (-3025 2900);
PAINT SKYBLUE (-3025 2900);
FORCEPROP 1 LAST PART_NUMBER CH4104K1B00
J 2
(-3025 2700);
DISPLAY 0.489362 (-3025 2700);
PAINT SKYBLUE (-3025 2700);
FORCEPROP 1 LAST VALUE 0.1UF
J 2
(-3025 2950);
DISPLAY 0.489362 (-3025 2950);
PAINT SKYBLUE (-3025 2950);
FORCEPROP 1 LAST TOLERANCE 10%
J 2
(-3025 2850);
DISPLAY 0.489362 (-3025 2850);
PAINT SKYBLUE (-3025 2850);
FORCEPROP 1 LAST MATERIAL X7R
J 2
(-3025 2800);
DISPLAY 0.489362 (-3025 2800);
PAINT SKYBLUE (-3025 2800);
FORCEPROP 1 LAST PATH I379
J 2
(-3025 3000);
DISPLAY 0.978723 (-3025 3000);
PAINT WHITE (-3025 3000);
DISPLAY INVISIBLE (-3025 3000);
FORCEPROP 2 LAST CDS_LIB pure_quanta
J 0
(-2975 2850);
DISPLAY INVISIBLE (-2975 2850);
FORCEADD UNIVERSAL_GND..1
R 2
(-2975 2650);
FORCEPROP 3 LASTPIN (-2975 2700) SIG_NAME GND\g
J 0
(-2965 2710);
DISPLAY 0.659574 (-2965 2710);
PAINT MONO (-2965 2710);
DISPLAY INVISIBLE (-2965 2710);
FORCEPROP 1 LAST HDL_POWER GND
J 1
(-3000 2575);
DISPLAY 0.872340 (-3000 2575);
PAINT GREEN (-3000 2575);
DISPLAY INVISIBLE (-3000 2575);
FORCEPROP 1 LAST PATH I380
J 2
(-3050 2650);
DISPLAY 0.872340 (-3050 2650);
PAINT AQUA (-3050 2650);
DISPLAY INVISIBLE (-3050 2650);
FORCEPROP 2 LAST CDS_LIB pure_quanta_power
J 0
(-2975 2650);
DISPLAY INVISIBLE (-2975 2650);
FORCEADD UNIVERSAL_POWER..1
(-1600 3225);
FORCEPROP 3 LASTPIN (-1600 3175) SIG_NAME PVDD18_S5_P0\g
J 0
(-1590 3185);
DISPLAY 0.659574 (-1590 3185);
PAINT MONO (-1590 3185);
DISPLAY INVISIBLE (-1590 3185);
FORCEPROP 1 LAST HDL_POWER PVDD18_S5_P0
J 1
(-1600 3275);
DISPLAY 0.489362 (-1600 3275);
PAINT GREEN (-1600 3275);
FORCEPROP 1 LAST PATH I382
J 0
(-1550 3250);
DISPLAY 0.872340 (-1550 3250);
PAINT AQUA (-1550 3250);
DISPLAY INVISIBLE (-1550 3250);
FORCEPROP 2 LAST CDS_LIB pure_quanta_power
J 0
(-1600 3225);
DISPLAY INVISIBLE (-1600 3225);
FORCEADD Q_RES..2
(-1600 2950);
FORCEPROP 1 LAST LOCATION R454
J 0
(-1555 3075);
DISPLAY 0.489362 (-1555 3075);
PAINT SKYBLUE (-1555 3075);
FORCEPROP 0 LAST $SEC 1
J 0
(-1550 3125);
DISPLAY 0.680851 (-1550 3125);
PAINT MONO (-1550 3125);
DISPLAY INVISIBLE (-1550 3125);
FORCEPROP 0 LAST CDS_SEC 1
J 0
(-1550 3125);
DISPLAY 1.021277 (-1550 3125);
DISPLAY INVISIBLE (-1550 3125);
FORCEPROP 1 LASTPIN (-1600 3050) $PN 1
J 0
(-1595 3012);
DISPLAY 0.489362 (-1595 3012);
PAINT MONO (-1595 3012);
FORCEPROP 1 LASTPIN (-1600 2850) $PN 2
J 0
(-1595 2860);
DISPLAY 0.489362 (-1595 2860);
PAINT MONO (-1595 2860);
FORCEPROP 1 LAST PACK_TYPE 0402LF
J 0
(-1575 2825);
DISPLAY 0.489362 (-1575 2825);
PAINT SKYBLUE (-1575 2825);
FORCEPROP 1 LAST VALUE 10K
J 0
(-1575 3025);
DISPLAY 0.489362 (-1575 3025);
PAINT SKYBLUE (-1575 3025);
FORCEPROP 1 LAST TOLERANCE 5%
J 0
(-1575 2975);
DISPLAY 0.489362 (-1575 2975);
PAINT SKYBLUE (-1575 2975);
FORCEPROP 1 LAST MATERIAL CHIP
J 0
(-1575 2875);
DISPLAY 0.489362 (-1575 2875);
PAINT SKYBLUE (-1575 2875);
FORCEPROP 1 LAST WATTAGE 1/16W
J 0
(-1575 2925);
DISPLAY 0.489362 (-1575 2925);
PAINT SKYBLUE (-1575 2925);
FORCEPROP 1 LAST PART_NUMBER TMP_QCS31002JB28
J 0
(-1585 2900);
DISPLAY 0.638298 (-1585 2900);
PAINT SKYBLUE (-1585 2900);
DISPLAY INVISIBLE (-1585 2900);
FORCEPROP 1 LAST PATH I383
J 0
(-1550 3125);
DISPLAY 0.978723 (-1550 3125);
PAINT WHITE (-1550 3125);
DISPLAY INVISIBLE (-1550 3125);
FORCEPROP 2 LAST BOM_COST I/O CONNECTOR
J 0
(-1575 3075);
DISPLAY 0.680851 (-1575 3075);
DISPLAY INVISIBLE (-1575 3075);
FORCEPROP 2 LAST CDS_LIB pure_quanta
J 0
(-1600 2950);
DISPLAY INVISIBLE (-1600 2950);
FORCEADD OFFPAGE..2
(-875 2550);
FORCEPROP 2 LAST $XR0 29 
J 0
(-686 2550);
DISPLAY 0.638298 (-686 2550);
PAINT MONO (-686 2550);
FORCEPROP 2 LAST CDS_LIB standard
J 0
(-875 2550);
DISPLAY INVISIBLE (-875 2550);
FORCEPROP 1 LAST OFFPAGE TRUE
J 0
(-550 2425);
DISPLAY 0.872340 (-550 2425);
PAINT GREEN (-550 2425);
DISPLAY INVISIBLE (-550 2425);
FORCEPROP 1 LAST COMMENT_BODY TRUE
J 0
(-920 2455);
DISPLAY 0.872340 (-920 2455);
PAINT GREEN (-920 2455);
DISPLAY INVISIBLE (-920 2455);
FORCEPROP 2 LAST PATH I384
J 0
(-700 2625);
DISPLAY 1.021277 (-700 2625);
DISPLAY INVISIBLE (-700 2625);
FORCEADD UNIVERSAL_GND..1
(-2875 2325);
FORCEPROP 3 LASTPIN (-2875 2375) SIG_NAME GND\g
J 0
(-2865 2385);
DISPLAY 0.659574 (-2865 2385);
PAINT MONO (-2865 2385);
DISPLAY INVISIBLE (-2865 2385);
FORCEPROP 1 LAST HDL_POWER GND
J 1
(-2850 2250);
DISPLAY 0.489362 (-2850 2250);
PAINT GREEN (-2850 2250);
FORCEPROP 1 LAST PATH I385
J 0
(-2800 2325);
DISPLAY 0.872340 (-2800 2325);
PAINT AQUA (-2800 2325);
DISPLAY INVISIBLE (-2800 2325);
FORCEPROP 2 LAST CDS_LIB pure_quanta_power
J 0
(-2875 2325);
DISPLAY INVISIBLE (-2875 2325);
FORCEADD VCC_CORE..1
(-2900 3125);
FORCEPROP 3 LASTPIN (-2900 3075) SIG_NAME P1V8_STBY\g
J 0
(-2890 3085);
DISPLAY 0.659574 (-2890 3085);
PAINT MONO (-2890 3085);
DISPLAY INVISIBLE (-2890 3085);
FORCEPROP 1 LAST HDL_POWER P1V8_STBY
J 1
(-2900 3175);
DISPLAY 0.489362 (-2900 3175);
PAINT GREEN (-2900 3175);
FORCEPROP 1 LAST PATH I386
J 0
(-2850 3150);
DISPLAY 0.872340 (-2850 3150);
PAINT AQUA (-2850 3150);
DISPLAY INVISIBLE (-2850 3150);
FORCEPROP 2 LAST CDS_LIB pure_quanta_power
J 0
(-2900 3125);
DISPLAY INVISIBLE (-2900 3125);
FORCEADD Q_CAP_DIFFBUS..2
(-2450 4250);
FORCEPROP 1 LAST LOCATION C11
J 0
(-2625 4250);
DISPLAY 0.489362 (-2625 4250);
PAINT SKYBLUE (-2625 4250);
FORCEPROP 0 LAST $SEC 1
J 0
(-2325 4275);
DISPLAY 0.680851 (-2325 4275);
PAINT MONO (-2325 4275);
DISPLAY INVISIBLE (-2325 4275);
FORCEPROP 0 LAST CDS_SEC 1
J 0
(-2325 4275);
DISPLAY 1.021277 (-2325 4275);
DISPLAY INVISIBLE (-2325 4275);
FORCEPROP 0 LASTPIN (-2525 4250) $PN 1
J 2
(-2535 4260);
DISPLAY 0.489362 (-2535 4260);
PAINT MONO (-2535 4260);
FORCEPROP 0 LASTPIN (-2375 4250) $PN 2
J 0
(-2365 4260);
DISPLAY 0.489362 (-2365 4260);
PAINT MONO (-2365 4260);
FORCEPROP 2 LAST VALUE DIFF BUS_0.22UF
J 0
(-2325 4250);
DISPLAY 0.489362 (-2325 4250);
PAINT SKYBLUE (-2325 4250);
FORCEPROP 0 LAST PACK_TYPE C0402
J 0
(-2150 4350);
DISPLAY 0.808511 (-2150 4350);
PAINT SKYBLUE (-2150 4350);
DISPLAY INVISIBLE (-2150 4350);
FORCEPROP 0 LAST VOLTAGE 16V
J 0
(-2500 4350);
DISPLAY 0.808511 (-2500 4350);
PAINT SKYBLUE (-2500 4350);
DISPLAY INVISIBLE (-2500 4350);
FORCEPROP 1 LAST PART_NUMBER SP_CH4223K1B00
J 0
(-2350 4300);
DISPLAY 0.723404 (-2350 4300);
PAINT SKYBLUE (-2350 4300);
DISPLAY INVISIBLE (-2350 4300);
FORCEPROP 0 LAST TOLERANCE 10%
J 0
(-2325 4350);
DISPLAY 0.808511 (-2325 4350);
PAINT SKYBLUE (-2325 4350);
DISPLAY INVISIBLE (-2325 4350);
FORCEPROP 1 LAST MATERIAL X7R
J 0
(-2484 4304);
DISPLAY 0.723404 (-2484 4304);
PAINT SKYBLUE (-2484 4304);
DISPLAY INVISIBLE (-2484 4304);
FORCEPROP 1 LAST PATH I387
J 0
(-2450 4250);
DISPLAY 0.723404 (-2450 4250);
DISPLAY INVISIBLE (-2450 4250);
FORCEPROP 1 LAST PIN_NAMES_ROTATE True
J 0
(-2450 4250);
DISPLAY 0.489362 (-2450 4250);
PAINT GREEN (-2450 4250);
DISPLAY INVISIBLE (-2450 4250);
FORCEPROP 1 LAST CDS_LMAN_SYM_OUTLINE -25,50,25,-50
J 0
(-2450 4250);
DISPLAY 0.468085 (-2450 4250);
PAINT GREEN (-2450 4250);
DISPLAY INVISIBLE (-2450 4250);
FORCEPROP 2 LAST CDS_LIB pure_quanta
J 0
(-2450 4250);
DISPLAY INVISIBLE (-2450 4250);
FORCEADD Q_CAP_DIFFBUS..2
(-2450 4300);
FORCEPROP 1 LAST LOCATION C10
J 0
(-2625 4300);
DISPLAY 0.489362 (-2625 4300);
PAINT SKYBLUE (-2625 4300);
FORCEPROP 0 LAST $SEC 1
J 0
(-2325 4325);
DISPLAY 0.680851 (-2325 4325);
PAINT MONO (-2325 4325);
DISPLAY INVISIBLE (-2325 4325);
FORCEPROP 0 LAST CDS_SEC 1
J 0
(-2325 4325);
DISPLAY 1.021277 (-2325 4325);
DISPLAY INVISIBLE (-2325 4325);
FORCEPROP 0 LASTPIN (-2525 4300) $PN 1
J 2
(-2535 4310);
DISPLAY 0.489362 (-2535 4310);
PAINT MONO (-2535 4310);
FORCEPROP 0 LASTPIN (-2375 4300) $PN 2
J 0
(-2365 4310);
DISPLAY 0.489362 (-2365 4310);
PAINT MONO (-2365 4310);
FORCEPROP 2 LAST VALUE DIFF BUS_0.22UF
J 0
(-2325 4300);
DISPLAY 0.489362 (-2325 4300);
PAINT SKYBLUE (-2325 4300);
FORCEPROP 0 LAST PACK_TYPE C0402
J 0
(-2150 4400);
DISPLAY 0.808511 (-2150 4400);
PAINT SKYBLUE (-2150 4400);
DISPLAY INVISIBLE (-2150 4400);
FORCEPROP 0 LAST VOLTAGE 16V
J 0
(-2500 4400);
DISPLAY 0.808511 (-2500 4400);
PAINT SKYBLUE (-2500 4400);
DISPLAY INVISIBLE (-2500 4400);
FORCEPROP 1 LAST PART_NUMBER SP_CH4223K1B00
J 0
(-2350 4350);
DISPLAY 0.723404 (-2350 4350);
PAINT SKYBLUE (-2350 4350);
DISPLAY INVISIBLE (-2350 4350);
FORCEPROP 0 LAST TOLERANCE 10%
J 0
(-2325 4400);
DISPLAY 0.808511 (-2325 4400);
PAINT SKYBLUE (-2325 4400);
DISPLAY INVISIBLE (-2325 4400);
FORCEPROP 1 LAST MATERIAL X7R
J 0
(-2484 4354);
DISPLAY 0.723404 (-2484 4354);
PAINT SKYBLUE (-2484 4354);
DISPLAY INVISIBLE (-2484 4354);
FORCEPROP 1 LAST PATH I388
J 0
(-2450 4300);
DISPLAY 0.723404 (-2450 4300);
DISPLAY INVISIBLE (-2450 4300);
FORCEPROP 1 LAST PIN_NAMES_ROTATE True
J 0
(-2450 4300);
DISPLAY 0.489362 (-2450 4300);
PAINT GREEN (-2450 4300);
DISPLAY INVISIBLE (-2450 4300);
FORCEPROP 1 LAST CDS_LMAN_SYM_OUTLINE -25,50,25,-50
J 0
(-2450 4300);
DISPLAY 0.468085 (-2450 4300);
PAINT GREEN (-2450 4300);
DISPLAY INVISIBLE (-2450 4300);
FORCEPROP 2 LAST CDS_LIB pure_quanta
J 0
(-2450 4300);
DISPLAY INVISIBLE (-2450 4300);
FORCEADD OFFPAGE..4
(-1200 4950);
FORCEPROP 2 LAST $XR0 145 
J 0
(-1014 4950);
DISPLAY 0.638298 (-1014 4950);
PAINT MONO (-1014 4950);
FORCEPROP 2 LAST CDS_LIB standard
J 0
(-1200 4950);
DISPLAY INVISIBLE (-1200 4950);
FORCEPROP 1 LAST OFFPAGE TRUE
J 0
(-875 4825);
DISPLAY 0.872340 (-875 4825);
PAINT GREEN (-875 4825);
DISPLAY INVISIBLE (-875 4825);
FORCEPROP 1 LAST COMMENT_BODY TRUE
J 0
(-1225 4850);
DISPLAY 0.872340 (-1225 4850);
PAINT GREEN (-1225 4850);
DISPLAY INVISIBLE (-1225 4850);
FORCEPROP 2 LAST PATH I389
J 0
(-1000 5000);
DISPLAY 1.021277 (-1000 5000);
DISPLAY INVISIBLE (-1000 5000);
FORCEADD OFFPAGE..4
(-1200 4900);
FORCEPROP 2 LAST $XR0 145 
J 0
(-1014 4900);
DISPLAY 0.638298 (-1014 4900);
PAINT MONO (-1014 4900);
FORCEPROP 2 LAST CDS_LIB standard
J 0
(-1200 4900);
DISPLAY INVISIBLE (-1200 4900);
FORCEPROP 1 LAST OFFPAGE TRUE
J 0
(-875 4775);
DISPLAY 0.872340 (-875 4775);
PAINT GREEN (-875 4775);
DISPLAY INVISIBLE (-875 4775);
FORCEPROP 1 LAST COMMENT_BODY TRUE
J 0
(-1225 4800);
DISPLAY 0.872340 (-1225 4800);
PAINT GREEN (-1225 4800);
DISPLAY INVISIBLE (-1225 4800);
FORCEPROP 2 LAST PATH I390
J 0
(-1000 4950);
DISPLAY 1.021277 (-1000 4950);
DISPLAY INVISIBLE (-1000 4950);
FORCEADD Q_CAP_DIFFBUS..2
(-2425 4900);
FORCEPROP 1 LAST LOCATION C29
J 0
(-2625 4900);
DISPLAY 0.489362 (-2625 4900);
PAINT SKYBLUE (-2625 4900);
FORCEPROP 0 LAST $SEC 1
J 0
(-2600 4950);
DISPLAY 0.680851 (-2600 4950);
PAINT MONO (-2600 4950);
DISPLAY INVISIBLE (-2600 4950);
FORCEPROP 0 LAST CDS_SEC 1
J 0
(-2600 4950);
DISPLAY 1.021277 (-2600 4950);
DISPLAY INVISIBLE (-2600 4950);
FORCEPROP 0 LASTPIN (-2500 4900) $PN 1
J 2
(-2510 4910);
DISPLAY 0.489362 (-2510 4910);
PAINT MONO (-2510 4910);
FORCEPROP 0 LASTPIN (-2350 4900) $PN 2
J 0
(-2340 4910);
DISPLAY 0.489362 (-2340 4910);
PAINT MONO (-2340 4910);
FORCEPROP 2 LAST VALUE DIFF BUS_0.33UF
J 0
(-2300 4900);
DISPLAY 0.489362 (-2300 4900);
PAINT SKYBLUE (-2300 4900);
FORCEPROP 0 LAST PACK_TYPE C0402
J 0
(-2325 4875);
DISPLAY 0.489362 (-2325 4875);
PAINT SKYBLUE (-2325 4875);
DISPLAY INVISIBLE (-2325 4875);
FORCEPROP 0 LAST VOLTAGE 6.3V
J 0
(-2175 4875);
DISPLAY 0.489362 (-2175 4875);
PAINT SKYBLUE (-2175 4875);
DISPLAY INVISIBLE (-2175 4875);
FORCEPROP 1 LAST PART_NUMBER SP_CH4331KEB01
J 0
(-2575 4925);
DISPLAY 0.489362 (-2575 4925);
PAINT SKYBLUE (-2575 4925);
DISPLAY INVISIBLE (-2575 4925);
FORCEPROP 0 LAST TOLERANCE 10%
J 0
(-2075 4875);
DISPLAY 0.489362 (-2075 4875);
PAINT SKYBLUE (-2075 4875);
DISPLAY INVISIBLE (-2075 4875);
FORCEPROP 1 LAST MATERIAL X6S
J 0
(-2575 4875);
DISPLAY 0.489362 (-2575 4875);
PAINT SKYBLUE (-2575 4875);
DISPLAY INVISIBLE (-2575 4875);
FORCEPROP 1 LAST PATH I391
J 0
(-2425 4900);
DISPLAY 0.723404 (-2425 4900);
DISPLAY INVISIBLE (-2425 4900);
FORCEPROP 2 LAST CDS_LIB pure_quanta
J 0
(-2425 4900);
DISPLAY INVISIBLE (-2425 4900);
FORCEPROP 1 LAST CDS_LMAN_SYM_OUTLINE -25,50,25,-50
J 0
(-2425 4900);
DISPLAY 0.468085 (-2425 4900);
PAINT GREEN (-2425 4900);
DISPLAY INVISIBLE (-2425 4900);
FORCEPROP 1 LAST PIN_NAMES_ROTATE TRUE
J 0
(-2425 4900);
DISPLAY 0.489362 (-2425 4900);
PAINT GREEN (-2425 4900);
DISPLAY INVISIBLE (-2425 4900);
FORCEADD Q_CAP_DIFFBUS..2
(-2425 4950);
FORCEPROP 1 LAST LOCATION C28
J 0
(-2625 4950);
DISPLAY 0.489362 (-2625 4950);
PAINT SKYBLUE (-2625 4950);
FORCEPROP 0 LAST $SEC 1
J 0
(-2600 5000);
DISPLAY 0.680851 (-2600 5000);
PAINT MONO (-2600 5000);
DISPLAY INVISIBLE (-2600 5000);
FORCEPROP 0 LAST CDS_SEC 1
J 0
(-2600 5000);
DISPLAY 1.021277 (-2600 5000);
DISPLAY INVISIBLE (-2600 5000);
FORCEPROP 0 LASTPIN (-2500 4950) $PN 1
J 2
(-2510 4960);
DISPLAY 0.489362 (-2510 4960);
PAINT MONO (-2510 4960);
FORCEPROP 0 LASTPIN (-2350 4950) $PN 2
J 0
(-2340 4960);
DISPLAY 0.489362 (-2340 4960);
PAINT MONO (-2340 4960);
FORCEPROP 2 LAST VALUE DIFF BUS_0.33UF
J 0
(-2300 4950);
DISPLAY 0.489362 (-2300 4950);
PAINT SKYBLUE (-2300 4950);
FORCEPROP 1 LAST PART_NUMBER SP_CH4331KEB01
J 0
(-2550 5000);
DISPLAY 0.489362 (-2550 5000);
PAINT SKYBLUE (-2550 5000);
FORCEPROP 0 LAST PACK_TYPE C0402
J 0
(-2325 4925);
DISPLAY 0.489362 (-2325 4925);
PAINT SKYBLUE (-2325 4925);
DISPLAY INVISIBLE (-2325 4925);
FORCEPROP 0 LAST VOLTAGE 6.3V
J 0
(-2175 4925);
DISPLAY 0.489362 (-2175 4925);
PAINT SKYBLUE (-2175 4925);
DISPLAY INVISIBLE (-2175 4925);
FORCEPROP 0 LAST TOLERANCE 10%
J 0
(-2075 4925);
DISPLAY 0.489362 (-2075 4925);
PAINT SKYBLUE (-2075 4925);
DISPLAY INVISIBLE (-2075 4925);
FORCEPROP 1 LAST MATERIAL X6S
J 0
(-2575 4925);
DISPLAY 0.489362 (-2575 4925);
PAINT SKYBLUE (-2575 4925);
DISPLAY INVISIBLE (-2575 4925);
FORCEPROP 1 LAST PATH I392
J 0
(-2425 4950);
DISPLAY 0.723404 (-2425 4950);
DISPLAY INVISIBLE (-2425 4950);
FORCEPROP 2 LAST CDS_LIB pure_quanta
J 0
(-2425 4950);
DISPLAY INVISIBLE (-2425 4950);
FORCEPROP 1 LAST CDS_LMAN_SYM_OUTLINE -25,50,25,-50
J 0
(-2425 4950);
DISPLAY 0.468085 (-2425 4950);
PAINT GREEN (-2425 4950);
DISPLAY INVISIBLE (-2425 4950);
FORCEPROP 1 LAST PIN_NAMES_ROTATE TRUE
J 0
(-2425 4950);
DISPLAY 0.489362 (-2425 4950);
PAINT GREEN (-2425 4950);
DISPLAY INVISIBLE (-2425 4950);
FORCEADD Q_RES..1
(-6950 5550);
FORCEPROP 1 LAST LOCATION R462
J 0
(-6825 5550);
DISPLAY 0.489362 (-6825 5550);
PAINT SKYBLUE (-6825 5550);
FORCEPROP 0 LAST $SEC 1
J 0
(-6850 5575);
DISPLAY 0.680851 (-6850 5575);
PAINT MONO (-6850 5575);
DISPLAY INVISIBLE (-6850 5575);
FORCEPROP 0 LAST CDS_SEC 1
J 0
(-6850 5575);
DISPLAY 1.021277 (-6850 5575);
DISPLAY INVISIBLE (-6850 5575);
FORCEPROP 1 LASTPIN (-7050 5550) $PN 1
J 0
(-7038 5562);
DISPLAY 0.489362 (-7038 5562);
PAINT MONO (-7038 5562);
FORCEPROP 1 LASTPIN (-6850 5550) $PN 2
J 0
(-6888 5562);
DISPLAY 0.489362 (-6888 5562);
PAINT MONO (-6888 5562);
FORCEPROP 1 LAST VALUE 33
J 2
(-7050 5550);
DISPLAY 0.489362 (-7050 5550);
PAINT SKYBLUE (-7050 5550);
FORCEPROP 2 LAST CDS_LIB pure_quanta
J 0
(-6950 5550);
DISPLAY INVISIBLE (-6950 5550);
FORCEPROP 1 LAST PATH I393
J 0
(-7000 5700);
DISPLAY 0.978723 (-7000 5700);
PAINT WHITE (-7000 5700);
DISPLAY INVISIBLE (-7000 5700);
FORCEPROP 1 LAST PACK_TYPE 0402LF
J 0
(-6900 5475);
DISPLAY 0.489362 (-6900 5475);
PAINT SKYBLUE (-6900 5475);
DISPLAY INVISIBLE (-6900 5475);
FORCEPROP 1 LAST PART_NUMBER CS03302JB29
J 0
(-6925 5600);
DISPLAY 0.489362 (-6925 5600);
PAINT SKYBLUE (-6925 5600);
DISPLAY INVISIBLE (-6925 5600);
FORCEPROP 1 LAST TOLERANCE 5%
J 0
(-6975 5475);
DISPLAY 0.489362 (-6975 5475);
PAINT SKYBLUE (-6975 5475);
DISPLAY INVISIBLE (-6975 5475);
FORCEPROP 1 LAST MATERIAL CHIP
J 0
(-6525 5475);
DISPLAY 0.489362 (-6525 5475);
PAINT SKYBLUE (-6525 5475);
DISPLAY INVISIBLE (-6525 5475);
FORCEPROP 1 LAST WATTAGE 1/16W
J 2
(-6550 5475);
DISPLAY 0.489362 (-6550 5475);
PAINT SKYBLUE (-6550 5475);
DISPLAY INVISIBLE (-6550 5475);
FORCEADD OFFPAGE..2
R 2
(-7775 5550);
FORCEPROP 2 LAST $XR2 117 
J 0
(-8209 5550);
DISPLAY 0.638298 (-8209 5550);
PAINT MONO (-8209 5550);
FORCEPROP 2 LAST $XR1 80 
J 0
(-8089 5550);
DISPLAY 0.638298 (-8089 5550);
PAINT MONO (-8089 5550);
FORCEPROP 2 LAST $XR0 29 
J 0
(-7999 5550);
DISPLAY 0.638298 (-7999 5550);
PAINT MONO (-7999 5550);
FORCEPROP 1 LAST COMMENT_BODY TRUE
J 2
(-7730 5455);
DISPLAY 0.872340 (-7730 5455);
PAINT PEACH (-7730 5455);
DISPLAY INVISIBLE (-7730 5455);
FORCEPROP 1 LAST OFFPAGE TRUE
J 2
(-8100 5425);
DISPLAY 0.872340 (-8100 5425);
PAINT GREEN (-8100 5425);
DISPLAY INVISIBLE (-8100 5425);
FORCEPROP 2 LAST PATH I394
J 0
(-7975 5600);
DISPLAY 0.680851 (-7975 5600);
DISPLAY INVISIBLE (-7975 5600);
FORCEPROP 2 LAST CDS_LIB standard
J 2
(-7775 5550);
DISPLAY INVISIBLE (-7775 5550);
FORCEADD UNIVERSAL_POWER..1
(-8125 2625);
FORCEPROP 3 LASTPIN (-8125 2575) SIG_NAME PVDD18_S5_P0\g
J 0
(-8115 2585);
DISPLAY 0.659574 (-8115 2585);
PAINT MONO (-8115 2585);
DISPLAY INVISIBLE (-8115 2585);
FORCEPROP 1 LAST HDL_POWER PVDD18_S5_P0
J 1
(-8125 2675);
DISPLAY 0.489362 (-8125 2675);
PAINT GREEN (-8125 2675);
FORCEPROP 1 LAST PATH I395
J 0
(-8075 2650);
DISPLAY 0.872340 (-8075 2650);
PAINT AQUA (-8075 2650);
DISPLAY INVISIBLE (-8075 2650);
FORCEPROP 2 LAST CDS_LIB pure_quanta_power
J 0
(-8125 2625);
DISPLAY INVISIBLE (-8125 2625);
FORCEADD Q_RES..1
(-7750 2375);
FORCEPROP 1 LAST LOCATION R1503
J 0
(-7625 2375);
DISPLAY 0.489362 (-7625 2375);
PAINT SKYBLUE (-7625 2375);
FORCEPROP 0 LAST $SEC 1
J 0
(-7625 2400);
DISPLAY 0.680851 (-7625 2400);
PAINT MONO (-7625 2400);
DISPLAY INVISIBLE (-7625 2400);
FORCEPROP 0 LAST CDS_SEC 1
J 0
(-7625 2400);
DISPLAY 0.680851 (-7625 2400);
DISPLAY INVISIBLE (-7625 2400);
FORCEPROP 1 LASTPIN (-7850 2375) $PN 1
J 0
(-7838 2387);
DISPLAY 0.489362 (-7838 2387);
PAINT MONO (-7838 2387);
FORCEPROP 1 LASTPIN (-7650 2375) $PN 2
J 0
(-7688 2387);
DISPLAY 0.489362 (-7688 2387);
PAINT MONO (-7688 2387);
FORCEPROP 1 LAST VALUE 30K
J 2
(-7850 2375);
DISPLAY 0.489362 (-7850 2375);
PAINT SKYBLUE (-7850 2375);
FORCEPROP 1 LAST PACK_TYPE 0402LF
J 0
(-7700 2300);
DISPLAY 0.489362 (-7700 2300);
PAINT SKYBLUE (-7700 2300);
DISPLAY INVISIBLE (-7700 2300);
FORCEPROP 1 LAST PART_NUMBER CS33002FB13
J 0
(-7725 2425);
DISPLAY 0.489362 (-7725 2425);
PAINT SKYBLUE (-7725 2425);
DISPLAY INVISIBLE (-7725 2425);
FORCEPROP 1 LAST TOLERANCE 1%
J 0
(-7775 2300);
DISPLAY 0.489362 (-7775 2300);
PAINT SKYBLUE (-7775 2300);
DISPLAY INVISIBLE (-7775 2300);
FORCEPROP 1 LAST MATERIAL CHIP
J 0
(-7325 2300);
DISPLAY 0.489362 (-7325 2300);
PAINT SKYBLUE (-7325 2300);
DISPLAY INVISIBLE (-7325 2300);
FORCEPROP 1 LAST WATTAGE 1/16W
J 2
(-7350 2300);
DISPLAY 0.489362 (-7350 2300);
PAINT SKYBLUE (-7350 2300);
DISPLAY INVISIBLE (-7350 2300);
FORCEPROP 1 LAST PATH I396
J 0
(-7800 2525);
DISPLAY 0.978723 (-7800 2525);
PAINT WHITE (-7800 2525);
DISPLAY INVISIBLE (-7800 2525);
FORCEPROP 2 LAST CDS_LIB pure_quanta
J 0
(-7750 2375);
DISPLAY INVISIBLE (-7750 2375);
FORCEADD Q_RES..1
(-7750 2325);
FORCEPROP 1 LAST LOCATION R1504
J 0
(-7625 2325);
DISPLAY 0.489362 (-7625 2325);
PAINT SKYBLUE (-7625 2325);
FORCEPROP 0 LAST $SEC 1
J 0
(-7625 2375);
DISPLAY 0.680851 (-7625 2375);
PAINT MONO (-7625 2375);
DISPLAY INVISIBLE (-7625 2375);
FORCEPROP 0 LAST CDS_SEC 1
J 0
(-7625 2375);
DISPLAY 0.680851 (-7625 2375);
DISPLAY INVISIBLE (-7625 2375);
FORCEPROP 1 LASTPIN (-7850 2325) $PN 1
J 0
(-7838 2337);
DISPLAY 0.489362 (-7838 2337);
PAINT MONO (-7838 2337);
FORCEPROP 1 LASTPIN (-7650 2325) $PN 2
J 0
(-7688 2337);
DISPLAY 0.489362 (-7688 2337);
PAINT MONO (-7688 2337);
FORCEPROP 1 LAST VALUE 30K
J 2
(-7850 2325);
DISPLAY 0.489362 (-7850 2325);
PAINT SKYBLUE (-7850 2325);
FORCEPROP 1 LAST PACK_TYPE 0402LF
J 0
(-7700 2250);
DISPLAY 0.489362 (-7700 2250);
PAINT SKYBLUE (-7700 2250);
DISPLAY INVISIBLE (-7700 2250);
FORCEPROP 1 LAST PART_NUMBER CS33002FB13
J 0
(-7725 2375);
DISPLAY 0.489362 (-7725 2375);
PAINT SKYBLUE (-7725 2375);
DISPLAY INVISIBLE (-7725 2375);
FORCEPROP 1 LAST TOLERANCE 1%
J 0
(-7775 2250);
DISPLAY 0.489362 (-7775 2250);
PAINT SKYBLUE (-7775 2250);
DISPLAY INVISIBLE (-7775 2250);
FORCEPROP 1 LAST MATERIAL CHIP
J 0
(-7325 2250);
DISPLAY 0.489362 (-7325 2250);
PAINT SKYBLUE (-7325 2250);
DISPLAY INVISIBLE (-7325 2250);
FORCEPROP 1 LAST WATTAGE 1/16W
J 2
(-7350 2250);
DISPLAY 0.489362 (-7350 2250);
PAINT SKYBLUE (-7350 2250);
DISPLAY INVISIBLE (-7350 2250);
FORCEPROP 1 LAST PATH I397
J 0
(-7800 2475);
DISPLAY 0.978723 (-7800 2475);
PAINT WHITE (-7800 2475);
DISPLAY INVISIBLE (-7800 2475);
FORCEPROP 2 LAST CDS_LIB pure_quanta
J 0
(-7750 2325);
DISPLAY INVISIBLE (-7750 2325);
FORCEADD Q_RES..1
(-7750 2275);
FORCEPROP 1 LAST LOCATION R1505
J 0
(-7625 2275);
DISPLAY 0.489362 (-7625 2275);
PAINT SKYBLUE (-7625 2275);
FORCEPROP 0 LAST $SEC 1
J 0
(-7625 2325);
DISPLAY 0.680851 (-7625 2325);
PAINT MONO (-7625 2325);
DISPLAY INVISIBLE (-7625 2325);
FORCEPROP 0 LAST CDS_SEC 1
J 0
(-7625 2325);
DISPLAY 0.680851 (-7625 2325);
DISPLAY INVISIBLE (-7625 2325);
FORCEPROP 1 LASTPIN (-7850 2275) $PN 1
J 0
(-7838 2287);
DISPLAY 0.489362 (-7838 2287);
PAINT MONO (-7838 2287);
FORCEPROP 1 LASTPIN (-7650 2275) $PN 2
J 0
(-7688 2287);
DISPLAY 0.489362 (-7688 2287);
PAINT MONO (-7688 2287);
FORCEPROP 1 LAST VALUE 30K
J 2
(-7850 2275);
DISPLAY 0.489362 (-7850 2275);
PAINT SKYBLUE (-7850 2275);
FORCEPROP 1 LAST PACK_TYPE 0402LF
J 0
(-7700 2200);
DISPLAY 0.489362 (-7700 2200);
PAINT SKYBLUE (-7700 2200);
DISPLAY INVISIBLE (-7700 2200);
FORCEPROP 1 LAST PART_NUMBER CS33002FB13
J 0
(-7725 2325);
DISPLAY 0.489362 (-7725 2325);
PAINT SKYBLUE (-7725 2325);
DISPLAY INVISIBLE (-7725 2325);
FORCEPROP 1 LAST TOLERANCE 1%
J 0
(-7775 2200);
DISPLAY 0.489362 (-7775 2200);
PAINT SKYBLUE (-7775 2200);
DISPLAY INVISIBLE (-7775 2200);
FORCEPROP 1 LAST MATERIAL CHIP
J 0
(-7325 2200);
DISPLAY 0.489362 (-7325 2200);
PAINT SKYBLUE (-7325 2200);
DISPLAY INVISIBLE (-7325 2200);
FORCEPROP 1 LAST WATTAGE 1/16W
J 2
(-7350 2200);
DISPLAY 0.489362 (-7350 2200);
PAINT SKYBLUE (-7350 2200);
DISPLAY INVISIBLE (-7350 2200);
FORCEPROP 1 LAST PATH I398
J 0
(-7800 2425);
DISPLAY 0.978723 (-7800 2425);
PAINT WHITE (-7800 2425);
DISPLAY INVISIBLE (-7800 2425);
FORCEPROP 2 LAST CDS_LIB pure_quanta
J 0
(-7750 2275);
DISPLAY INVISIBLE (-7750 2275);
FORCEADD Q_RES..1
(-7750 2225);
FORCEPROP 1 LAST LOCATION R1506
J 0
(-7625 2225);
DISPLAY 0.489362 (-7625 2225);
PAINT SKYBLUE (-7625 2225);
FORCEPROP 0 LAST $SEC 1
J 0
(-7625 2275);
DISPLAY 0.680851 (-7625 2275);
PAINT MONO (-7625 2275);
DISPLAY INVISIBLE (-7625 2275);
FORCEPROP 0 LAST CDS_SEC 1
J 0
(-7625 2275);
DISPLAY 0.680851 (-7625 2275);
DISPLAY INVISIBLE (-7625 2275);
FORCEPROP 1 LASTPIN (-7850 2225) $PN 1
J 0
(-7838 2237);
DISPLAY 0.489362 (-7838 2237);
PAINT MONO (-7838 2237);
FORCEPROP 1 LASTPIN (-7650 2225) $PN 2
J 0
(-7688 2237);
DISPLAY 0.489362 (-7688 2237);
PAINT MONO (-7688 2237);
FORCEPROP 1 LAST VALUE 30K
J 2
(-7850 2225);
DISPLAY 0.489362 (-7850 2225);
PAINT SKYBLUE (-7850 2225);
FORCEPROP 1 LAST PACK_TYPE 0402LF
J 0
(-7700 2150);
DISPLAY 0.489362 (-7700 2150);
PAINT SKYBLUE (-7700 2150);
DISPLAY INVISIBLE (-7700 2150);
FORCEPROP 1 LAST PART_NUMBER CS33002FB13
J 0
(-7725 2275);
DISPLAY 0.489362 (-7725 2275);
PAINT SKYBLUE (-7725 2275);
DISPLAY INVISIBLE (-7725 2275);
FORCEPROP 1 LAST TOLERANCE 1%
J 0
(-7775 2150);
DISPLAY 0.489362 (-7775 2150);
PAINT SKYBLUE (-7775 2150);
DISPLAY INVISIBLE (-7775 2150);
FORCEPROP 1 LAST MATERIAL CHIP
J 0
(-7325 2150);
DISPLAY 0.489362 (-7325 2150);
PAINT SKYBLUE (-7325 2150);
DISPLAY INVISIBLE (-7325 2150);
FORCEPROP 1 LAST WATTAGE 1/16W
J 2
(-7350 2150);
DISPLAY 0.489362 (-7350 2150);
PAINT SKYBLUE (-7350 2150);
DISPLAY INVISIBLE (-7350 2150);
FORCEPROP 1 LAST PATH I399
J 0
(-7800 2375);
DISPLAY 0.978723 (-7800 2375);
PAINT WHITE (-7800 2375);
DISPLAY INVISIBLE (-7800 2375);
FORCEPROP 2 LAST CDS_LIB pure_quanta
J 0
(-7750 2225);
DISPLAY INVISIBLE (-7750 2225);
FORCEADD OFFPAGE..2
(-6850 2375);
FORCEPROP 2 LAST $XR2 117 
J 0
(-6481 2375);
DISPLAY 0.638298 (-6481 2375);
PAINT MONO (-6481 2375);
FORCEPROP 2 LAST $XR1 80 
J 0
(-6571 2375);
DISPLAY 0.638298 (-6571 2375);
PAINT MONO (-6571 2375);
FORCEPROP 2 LAST $XR0 29 
J 0
(-6661 2375);
DISPLAY 0.638298 (-6661 2375);
PAINT MONO (-6661 2375);
FORCEPROP 2 LAST CDS_LIB standard
J 0
(-6850 2375);
DISPLAY INVISIBLE (-6850 2375);
FORCEPROP 1 LAST OFFPAGE TRUE
J 0
(-6525 2250);
DISPLAY 0.872340 (-6525 2250);
PAINT GREEN (-6525 2250);
DISPLAY INVISIBLE (-6525 2250);
FORCEPROP 1 LAST COMMENT_BODY TRUE
J 0
(-6895 2280);
DISPLAY 0.872340 (-6895 2280);
PAINT PEACH (-6895 2280);
DISPLAY INVISIBLE (-6895 2280);
FORCEPROP 2 LAST PATH I400
J 0
(-6675 2450);
DISPLAY 0.680851 (-6675 2450);
DISPLAY INVISIBLE (-6675 2450);
FORCEADD OFFPAGE..2
(-6850 2275);
FORCEPROP 2 LAST $XR2 117 
J 0
(-6481 2275);
DISPLAY 0.638298 (-6481 2275);
PAINT MONO (-6481 2275);
FORCEPROP 2 LAST $XR1 80 
J 0
(-6571 2275);
DISPLAY 0.638298 (-6571 2275);
PAINT MONO (-6571 2275);
FORCEPROP 2 LAST $XR0 29 
J 0
(-6661 2275);
DISPLAY 0.638298 (-6661 2275);
PAINT MONO (-6661 2275);
FORCEPROP 2 LAST CDS_LIB standard
J 0
(-6850 2275);
DISPLAY INVISIBLE (-6850 2275);
FORCEPROP 1 LAST OFFPAGE TRUE
J 0
(-6525 2150);
DISPLAY 0.872340 (-6525 2150);
PAINT GREEN (-6525 2150);
DISPLAY INVISIBLE (-6525 2150);
FORCEPROP 1 LAST COMMENT_BODY TRUE
J 0
(-6895 2180);
DISPLAY 0.872340 (-6895 2180);
PAINT PEACH (-6895 2180);
DISPLAY INVISIBLE (-6895 2180);
FORCEPROP 2 LAST PATH I401
J 0
(-6675 2350);
DISPLAY 0.680851 (-6675 2350);
DISPLAY INVISIBLE (-6675 2350);
FORCEADD OFFPAGE..2
(-6850 2325);
FORCEPROP 2 LAST $XR2 117 
J 0
(-6481 2325);
DISPLAY 0.638298 (-6481 2325);
PAINT MONO (-6481 2325);
FORCEPROP 2 LAST $XR1 80 
J 0
(-6571 2325);
DISPLAY 0.638298 (-6571 2325);
PAINT MONO (-6571 2325);
FORCEPROP 2 LAST $XR0 29 
J 0
(-6661 2325);
DISPLAY 0.638298 (-6661 2325);
PAINT MONO (-6661 2325);
FORCEPROP 2 LAST CDS_LIB standard
J 0
(-6850 2325);
DISPLAY INVISIBLE (-6850 2325);
FORCEPROP 1 LAST OFFPAGE TRUE
J 0
(-6525 2200);
DISPLAY 0.872340 (-6525 2200);
PAINT GREEN (-6525 2200);
DISPLAY INVISIBLE (-6525 2200);
FORCEPROP 1 LAST COMMENT_BODY TRUE
J 0
(-6895 2230);
DISPLAY 0.872340 (-6895 2230);
PAINT PEACH (-6895 2230);
DISPLAY INVISIBLE (-6895 2230);
FORCEPROP 2 LAST PATH I402
J 0
(-6675 2400);
DISPLAY 0.680851 (-6675 2400);
DISPLAY INVISIBLE (-6675 2400);
FORCEADD OFFPAGE..2
(-6850 2225);
FORCEPROP 2 LAST $XR2 117 
J 0
(-6481 2225);
DISPLAY 0.638298 (-6481 2225);
PAINT MONO (-6481 2225);
FORCEPROP 2 LAST $XR1 80 
J 0
(-6571 2225);
DISPLAY 0.638298 (-6571 2225);
PAINT MONO (-6571 2225);
FORCEPROP 2 LAST $XR0 29 
J 0
(-6661 2225);
DISPLAY 0.638298 (-6661 2225);
PAINT MONO (-6661 2225);
FORCEPROP 2 LAST CDS_LIB standard
J 0
(-6850 2225);
DISPLAY INVISIBLE (-6850 2225);
FORCEPROP 1 LAST OFFPAGE TRUE
J 0
(-6525 2100);
DISPLAY 0.872340 (-6525 2100);
PAINT GREEN (-6525 2100);
DISPLAY INVISIBLE (-6525 2100);
FORCEPROP 1 LAST COMMENT_BODY TRUE
J 0
(-6895 2130);
DISPLAY 0.872340 (-6895 2130);
PAINT PEACH (-6895 2130);
DISPLAY INVISIBLE (-6895 2130);
FORCEPROP 2 LAST PATH I403
J 0
(-6675 2300);
DISPLAY 0.680851 (-6675 2300);
DISPLAY INVISIBLE (-6675 2300);
FORCEADD OFFPAGE..2
(-6825 2150);
FORCEPROP 2 LAST $XR2 80 
J 0
(-6426 2150);
DISPLAY 0.638298 (-6426 2150);
PAINT MONO (-6426 2150);
FORCEPROP 2 LAST $XR1 29 
J 0
(-6516 2150);
DISPLAY 0.638298 (-6516 2150);
PAINT MONO (-6516 2150);
FORCEPROP 2 LAST $XR0 117 
J 0
(-6636 2150);
DISPLAY 0.638298 (-6636 2150);
PAINT MONO (-6636 2150);
FORCEPROP 2 LAST CDS_LIB standard
J 2
(-6825 2150);
DISPLAY INVISIBLE (-6825 2150);
FORCEPROP 1 LAST OFFPAGE TRUE
J 0
(-6500 2025);
DISPLAY 0.872340 (-6500 2025);
PAINT GREEN (-6500 2025);
DISPLAY INVISIBLE (-6500 2025);
FORCEPROP 1 LAST COMMENT_BODY TRUE
J 0
(-6870 2055);
DISPLAY 0.872340 (-6870 2055);
PAINT PEACH (-6870 2055);
DISPLAY INVISIBLE (-6870 2055);
FORCEPROP 2 LAST PATH I404
J 0
(-6500 2200);
DISPLAY 0.680851 (-6500 2200);
DISPLAY INVISIBLE (-6500 2200);
FORCEADD Q_RES..1
(-7750 2150);
FORCEPROP 1 LAST LOCATION R458
J 0
(-7625 2150);
DISPLAY 0.489362 (-7625 2150);
PAINT SKYBLUE (-7625 2150);
FORCEPROP 0 LAST $SEC 1
J 0
(-7625 2200);
DISPLAY 0.680851 (-7625 2200);
PAINT MONO (-7625 2200);
DISPLAY INVISIBLE (-7625 2200);
FORCEPROP 0 LAST CDS_SEC 1
J 0
(-7625 2200);
DISPLAY 0.680851 (-7625 2200);
DISPLAY INVISIBLE (-7625 2200);
FORCEPROP 1 LASTPIN (-7850 2150) $PN 1
J 0
(-7838 2162);
DISPLAY 0.489362 (-7838 2162);
PAINT MONO (-7838 2162);
FORCEPROP 1 LASTPIN (-7650 2150) $PN 2
J 0
(-7688 2162);
DISPLAY 0.489362 (-7688 2162);
PAINT MONO (-7688 2162);
FORCEPROP 1 LAST VALUE 30K
J 2
(-7850 2150);
DISPLAY 0.489362 (-7850 2150);
PAINT SKYBLUE (-7850 2150);
FORCEPROP 1 LAST PACK_TYPE 0402LF
J 0
(-7700 2075);
DISPLAY 0.489362 (-7700 2075);
PAINT SKYBLUE (-7700 2075);
DISPLAY INVISIBLE (-7700 2075);
FORCEPROP 1 LAST PART_NUMBER CS33002FB13
J 0
(-7725 2200);
DISPLAY 0.489362 (-7725 2200);
PAINT SKYBLUE (-7725 2200);
DISPLAY INVISIBLE (-7725 2200);
FORCEPROP 1 LAST TOLERANCE 1%
J 0
(-7775 2075);
DISPLAY 0.489362 (-7775 2075);
PAINT SKYBLUE (-7775 2075);
DISPLAY INVISIBLE (-7775 2075);
FORCEPROP 1 LAST MATERIAL CHIP
J 0
(-7325 2075);
DISPLAY 0.489362 (-7325 2075);
PAINT SKYBLUE (-7325 2075);
DISPLAY INVISIBLE (-7325 2075);
FORCEPROP 1 LAST WATTAGE 1/16W
J 2
(-7350 2075);
DISPLAY 0.489362 (-7350 2075);
PAINT SKYBLUE (-7350 2075);
DISPLAY INVISIBLE (-7350 2075);
FORCEPROP 1 LAST PATH I405
J 0
(-7800 2300);
DISPLAY 0.978723 (-7800 2300);
PAINT WHITE (-7800 2300);
DISPLAY INVISIBLE (-7800 2300);
FORCEPROP 2 LAST CDS_LIB pure_quanta
J 0
(-7750 2150);
DISPLAY INVISIBLE (-7750 2150);
FORCEADD Q_RES..1
(-6950 4450);
FORCEPROP 1 LAST LOCATION R473
J 0
(-6825 4450);
DISPLAY 0.489362 (-6825 4450);
PAINT SKYBLUE (-6825 4450);
FORCEPROP 0 LAST $SEC 1
J 0
(-6825 4475);
DISPLAY 0.680851 (-6825 4475);
PAINT MONO (-6825 4475);
DISPLAY INVISIBLE (-6825 4475);
FORCEPROP 0 LAST CDS_SEC 1
J 0
(-6825 4475);
DISPLAY 0.680851 (-6825 4475);
DISPLAY INVISIBLE (-6825 4475);
FORCEPROP 1 LASTPIN (-7050 4450) $PN 1
J 0
(-7038 4462);
DISPLAY 0.489362 (-7038 4462);
PAINT MONO (-7038 4462);
FORCEPROP 1 LASTPIN (-6850 4450) $PN 2
J 0
(-6888 4462);
DISPLAY 0.489362 (-6888 4462);
PAINT MONO (-6888 4462);
FORCEPROP 1 LAST VALUE 33
J 2
(-7050 4450);
DISPLAY 0.489362 (-7050 4450);
PAINT SKYBLUE (-7050 4450);
FORCEPROP 1 LAST PACK_TYPE 0402LF
J 0
(-6900 4375);
DISPLAY 0.489362 (-6900 4375);
PAINT SKYBLUE (-6900 4375);
DISPLAY INVISIBLE (-6900 4375);
FORCEPROP 1 LAST PART_NUMBER CS03302JB29
J 0
(-6925 4500);
DISPLAY 0.489362 (-6925 4500);
PAINT SKYBLUE (-6925 4500);
DISPLAY INVISIBLE (-6925 4500);
FORCEPROP 1 LAST TOLERANCE 5%
J 0
(-6975 4375);
DISPLAY 0.489362 (-6975 4375);
PAINT SKYBLUE (-6975 4375);
DISPLAY INVISIBLE (-6975 4375);
FORCEPROP 1 LAST MATERIAL CHIP
J 0
(-6525 4375);
DISPLAY 0.489362 (-6525 4375);
PAINT SKYBLUE (-6525 4375);
DISPLAY INVISIBLE (-6525 4375);
FORCEPROP 1 LAST WATTAGE 1/16W
J 2
(-6550 4375);
DISPLAY 0.489362 (-6550 4375);
PAINT SKYBLUE (-6550 4375);
DISPLAY INVISIBLE (-6550 4375);
FORCEPROP 1 LAST PATH I406
J 0
(-7000 4600);
DISPLAY 0.978723 (-7000 4600);
PAINT WHITE (-7000 4600);
DISPLAY INVISIBLE (-7000 4600);
FORCEPROP 2 LAST CDS_LIB pure_quanta
J 0
(-6950 4450);
DISPLAY INVISIBLE (-6950 4450);
FORCEADD Q_RES..1
(-6950 5900);
FORCEPROP 1 LAST LOCATION R459
J 0
(-6825 5900);
DISPLAY 0.489362 (-6825 5900);
PAINT SKYBLUE (-6825 5900);
FORCEPROP 0 LAST $SEC 1
J 0
(-6825 5925);
DISPLAY 0.680851 (-6825 5925);
PAINT MONO (-6825 5925);
DISPLAY INVISIBLE (-6825 5925);
FORCEPROP 0 LAST CDS_SEC 1
J 0
(-6825 5925);
DISPLAY 0.680851 (-6825 5925);
DISPLAY INVISIBLE (-6825 5925);
FORCEPROP 1 LASTPIN (-7050 5900) $PN 1
J 0
(-7038 5912);
DISPLAY 0.489362 (-7038 5912);
PAINT MONO (-7038 5912);
FORCEPROP 1 LASTPIN (-6850 5900) $PN 2
J 0
(-6888 5912);
DISPLAY 0.489362 (-6888 5912);
PAINT MONO (-6888 5912);
FORCEPROP 1 LAST VALUE 33
J 2
(-7050 5900);
DISPLAY 0.489362 (-7050 5900);
PAINT SKYBLUE (-7050 5900);
FORCEPROP 1 LAST PACK_TYPE 0402LF
J 0
(-6900 5825);
DISPLAY 0.489362 (-6900 5825);
PAINT SKYBLUE (-6900 5825);
DISPLAY INVISIBLE (-6900 5825);
FORCEPROP 1 LAST PART_NUMBER CS03302JB29
J 0
(-6925 5950);
DISPLAY 0.489362 (-6925 5950);
PAINT SKYBLUE (-6925 5950);
DISPLAY INVISIBLE (-6925 5950);
FORCEPROP 1 LAST TOLERANCE 5%
J 0
(-6975 5825);
DISPLAY 0.489362 (-6975 5825);
PAINT SKYBLUE (-6975 5825);
DISPLAY INVISIBLE (-6975 5825);
FORCEPROP 1 LAST MATERIAL CHIP
J 0
(-6525 5825);
DISPLAY 0.489362 (-6525 5825);
PAINT SKYBLUE (-6525 5825);
DISPLAY INVISIBLE (-6525 5825);
FORCEPROP 1 LAST WATTAGE 1/16W
J 2
(-6550 5825);
DISPLAY 0.489362 (-6550 5825);
PAINT SKYBLUE (-6550 5825);
DISPLAY INVISIBLE (-6550 5825);
FORCEPROP 1 LAST PATH I407
J 0
(-7000 6050);
DISPLAY 0.978723 (-7000 6050);
PAINT WHITE (-7000 6050);
DISPLAY INVISIBLE (-7000 6050);
FORCEPROP 2 LAST CDS_LIB pure_quanta
J 0
(-6950 5900);
DISPLAY INVISIBLE (-6950 5900);
FORCEADD Q_RES..1
(-6950 5850);
FORCEPROP 1 LAST LOCATION R460
J 0
(-6825 5850);
DISPLAY 0.489362 (-6825 5850);
PAINT SKYBLUE (-6825 5850);
FORCEPROP 0 LAST $SEC 1
J 0
(-6825 5875);
DISPLAY 0.680851 (-6825 5875);
PAINT MONO (-6825 5875);
DISPLAY INVISIBLE (-6825 5875);
FORCEPROP 0 LAST CDS_SEC 1
J 0
(-6825 5875);
DISPLAY 0.680851 (-6825 5875);
DISPLAY INVISIBLE (-6825 5875);
FORCEPROP 1 LASTPIN (-7050 5850) $PN 1
J 0
(-7038 5862);
DISPLAY 0.489362 (-7038 5862);
PAINT MONO (-7038 5862);
FORCEPROP 1 LASTPIN (-6850 5850) $PN 2
J 0
(-6888 5862);
DISPLAY 0.489362 (-6888 5862);
PAINT MONO (-6888 5862);
FORCEPROP 1 LAST VALUE 33
J 2
(-7050 5850);
DISPLAY 0.489362 (-7050 5850);
PAINT SKYBLUE (-7050 5850);
FORCEPROP 1 LAST WATTAGE 1/16W
J 2
(-6550 5775);
DISPLAY 0.489362 (-6550 5775);
PAINT SKYBLUE (-6550 5775);
DISPLAY INVISIBLE (-6550 5775);
FORCEPROP 1 LAST MATERIAL CHIP
J 0
(-6525 5775);
DISPLAY 0.489362 (-6525 5775);
PAINT SKYBLUE (-6525 5775);
DISPLAY INVISIBLE (-6525 5775);
FORCEPROP 1 LAST TOLERANCE 5%
J 0
(-6975 5775);
DISPLAY 0.489362 (-6975 5775);
PAINT SKYBLUE (-6975 5775);
DISPLAY INVISIBLE (-6975 5775);
FORCEPROP 1 LAST PART_NUMBER CS03302JB29
J 0
(-6925 5900);
DISPLAY 0.489362 (-6925 5900);
PAINT SKYBLUE (-6925 5900);
DISPLAY INVISIBLE (-6925 5900);
FORCEPROP 1 LAST PACK_TYPE 0402LF
J 0
(-6900 5775);
DISPLAY 0.489362 (-6900 5775);
PAINT SKYBLUE (-6900 5775);
DISPLAY INVISIBLE (-6900 5775);
FORCEPROP 1 LAST PATH I408
J 0
(-7000 6000);
DISPLAY 0.978723 (-7000 6000);
PAINT WHITE (-7000 6000);
DISPLAY INVISIBLE (-7000 6000);
FORCEPROP 2 LAST CDS_LIB pure_quanta
J 0
(-6950 5850);
DISPLAY INVISIBLE (-6950 5850);
FORCEADD Q_RES..1
(-6950 5650);
FORCEPROP 1 LAST LOCATION R461
J 0
(-6825 5650);
DISPLAY 0.489362 (-6825 5650);
PAINT SKYBLUE (-6825 5650);
FORCEPROP 0 LAST $SEC 1
J 0
(-6825 5675);
DISPLAY 0.680851 (-6825 5675);
PAINT MONO (-6825 5675);
DISPLAY INVISIBLE (-6825 5675);
FORCEPROP 0 LAST CDS_SEC 1
J 0
(-6825 5675);
DISPLAY 0.680851 (-6825 5675);
DISPLAY INVISIBLE (-6825 5675);
FORCEPROP 1 LASTPIN (-7050 5650) $PN 1
J 0
(-7038 5662);
DISPLAY 0.489362 (-7038 5662);
PAINT MONO (-7038 5662);
FORCEPROP 1 LASTPIN (-6850 5650) $PN 2
J 0
(-6888 5662);
DISPLAY 0.489362 (-6888 5662);
PAINT MONO (-6888 5662);
FORCEPROP 1 LAST VALUE 33
J 2
(-7050 5650);
DISPLAY 0.489362 (-7050 5650);
PAINT SKYBLUE (-7050 5650);
FORCEPROP 1 LAST PACK_TYPE 0402LF
J 0
(-6900 5575);
DISPLAY 0.489362 (-6900 5575);
PAINT SKYBLUE (-6900 5575);
DISPLAY INVISIBLE (-6900 5575);
FORCEPROP 1 LAST PART_NUMBER CS03302JB29
J 0
(-6925 5700);
DISPLAY 0.489362 (-6925 5700);
PAINT SKYBLUE (-6925 5700);
DISPLAY INVISIBLE (-6925 5700);
FORCEPROP 1 LAST TOLERANCE 5%
J 0
(-6975 5575);
DISPLAY 0.489362 (-6975 5575);
PAINT SKYBLUE (-6975 5575);
DISPLAY INVISIBLE (-6975 5575);
FORCEPROP 1 LAST MATERIAL CHIP
J 0
(-6525 5575);
DISPLAY 0.489362 (-6525 5575);
PAINT SKYBLUE (-6525 5575);
DISPLAY INVISIBLE (-6525 5575);
FORCEPROP 1 LAST WATTAGE 1/16W
J 2
(-6550 5575);
DISPLAY 0.489362 (-6550 5575);
PAINT SKYBLUE (-6550 5575);
DISPLAY INVISIBLE (-6550 5575);
FORCEPROP 1 LAST PATH I409
J 0
(-7000 5800);
DISPLAY 0.978723 (-7000 5800);
PAINT WHITE (-7000 5800);
DISPLAY INVISIBLE (-7000 5800);
FORCEPROP 2 LAST CDS_LIB pure_quanta
J 0
(-6950 5650);
DISPLAY INVISIBLE (-6950 5650);
FORCEADD Q_RES..1
(-6950 5250);
FORCEPROP 1 LAST LOCATION R464
J 0
(-6825 5250);
DISPLAY 0.489362 (-6825 5250);
PAINT SKYBLUE (-6825 5250);
FORCEPROP 0 LAST $SEC 1
J 0
(-6825 5275);
DISPLAY 0.680851 (-6825 5275);
PAINT MONO (-6825 5275);
DISPLAY INVISIBLE (-6825 5275);
FORCEPROP 0 LAST CDS_SEC 1
J 0
(-6825 5275);
DISPLAY 0.680851 (-6825 5275);
DISPLAY INVISIBLE (-6825 5275);
FORCEPROP 1 LASTPIN (-7050 5250) $PN 1
J 0
(-7038 5262);
DISPLAY 0.489362 (-7038 5262);
PAINT MONO (-7038 5262);
FORCEPROP 1 LASTPIN (-6850 5250) $PN 2
J 0
(-6888 5262);
DISPLAY 0.489362 (-6888 5262);
PAINT MONO (-6888 5262);
FORCEPROP 1 LAST VALUE 33
J 2
(-7050 5250);
DISPLAY 0.489362 (-7050 5250);
PAINT SKYBLUE (-7050 5250);
FORCEPROP 1 LAST PACK_TYPE 0402LF
J 0
(-6900 5175);
DISPLAY 0.489362 (-6900 5175);
PAINT SKYBLUE (-6900 5175);
DISPLAY INVISIBLE (-6900 5175);
FORCEPROP 1 LAST PART_NUMBER CS03302JB29
J 0
(-6925 5300);
DISPLAY 0.489362 (-6925 5300);
PAINT SKYBLUE (-6925 5300);
DISPLAY INVISIBLE (-6925 5300);
FORCEPROP 1 LAST TOLERANCE 5%
J 0
(-6975 5175);
DISPLAY 0.489362 (-6975 5175);
PAINT SKYBLUE (-6975 5175);
DISPLAY INVISIBLE (-6975 5175);
FORCEPROP 1 LAST MATERIAL CHIP
J 0
(-6525 5175);
DISPLAY 0.489362 (-6525 5175);
PAINT SKYBLUE (-6525 5175);
DISPLAY INVISIBLE (-6525 5175);
FORCEPROP 1 LAST WATTAGE 1/16W
J 2
(-6550 5175);
DISPLAY 0.489362 (-6550 5175);
PAINT SKYBLUE (-6550 5175);
DISPLAY INVISIBLE (-6550 5175);
FORCEPROP 1 LAST PATH I410
J 0
(-7000 5400);
DISPLAY 0.978723 (-7000 5400);
PAINT WHITE (-7000 5400);
DISPLAY INVISIBLE (-7000 5400);
FORCEPROP 2 LAST CDS_LIB pure_quanta
J 0
(-6950 5250);
DISPLAY INVISIBLE (-6950 5250);
FORCEADD Q_RES..1
(-6950 5200);
FORCEPROP 1 LAST LOCATION R465
J 0
(-6825 5200);
DISPLAY 0.489362 (-6825 5200);
PAINT SKYBLUE (-6825 5200);
FORCEPROP 0 LAST $SEC 1
J 0
(-6825 5225);
DISPLAY 0.680851 (-6825 5225);
PAINT MONO (-6825 5225);
DISPLAY INVISIBLE (-6825 5225);
FORCEPROP 0 LAST CDS_SEC 1
J 0
(-6825 5225);
DISPLAY 0.680851 (-6825 5225);
DISPLAY INVISIBLE (-6825 5225);
FORCEPROP 1 LASTPIN (-7050 5200) $PN 1
J 0
(-7038 5212);
DISPLAY 0.489362 (-7038 5212);
PAINT MONO (-7038 5212);
FORCEPROP 1 LASTPIN (-6850 5200) $PN 2
J 0
(-6888 5212);
DISPLAY 0.489362 (-6888 5212);
PAINT MONO (-6888 5212);
FORCEPROP 1 LAST VALUE 33
J 2
(-7050 5200);
DISPLAY 0.489362 (-7050 5200);
PAINT SKYBLUE (-7050 5200);
FORCEPROP 1 LAST PACK_TYPE 0402LF
J 0
(-6900 5125);
DISPLAY 0.489362 (-6900 5125);
PAINT SKYBLUE (-6900 5125);
DISPLAY INVISIBLE (-6900 5125);
FORCEPROP 1 LAST PART_NUMBER CS03302JB29
J 0
(-6925 5250);
DISPLAY 0.489362 (-6925 5250);
PAINT SKYBLUE (-6925 5250);
DISPLAY INVISIBLE (-6925 5250);
FORCEPROP 1 LAST TOLERANCE 5%
J 0
(-6975 5125);
DISPLAY 0.489362 (-6975 5125);
PAINT SKYBLUE (-6975 5125);
DISPLAY INVISIBLE (-6975 5125);
FORCEPROP 1 LAST MATERIAL CHIP
J 0
(-6525 5125);
DISPLAY 0.489362 (-6525 5125);
PAINT SKYBLUE (-6525 5125);
DISPLAY INVISIBLE (-6525 5125);
FORCEPROP 1 LAST WATTAGE 1/16W
J 2
(-6550 5125);
DISPLAY 0.489362 (-6550 5125);
PAINT SKYBLUE (-6550 5125);
DISPLAY INVISIBLE (-6550 5125);
FORCEPROP 1 LAST PATH I411
J 0
(-7000 5350);
DISPLAY 0.978723 (-7000 5350);
PAINT WHITE (-7000 5350);
DISPLAY INVISIBLE (-7000 5350);
FORCEPROP 2 LAST CDS_LIB pure_quanta
J 0
(-6950 5200);
DISPLAY INVISIBLE (-6950 5200);
FORCEADD Q_RES..1
(-6950 5150);
FORCEPROP 1 LAST LOCATION R466
J 0
(-6825 5150);
DISPLAY 0.489362 (-6825 5150);
PAINT SKYBLUE (-6825 5150);
FORCEPROP 0 LAST $SEC 1
J 0
(-6825 5175);
DISPLAY 0.680851 (-6825 5175);
PAINT MONO (-6825 5175);
DISPLAY INVISIBLE (-6825 5175);
FORCEPROP 0 LAST CDS_SEC 1
J 0
(-6825 5175);
DISPLAY 0.680851 (-6825 5175);
DISPLAY INVISIBLE (-6825 5175);
FORCEPROP 1 LASTPIN (-7050 5150) $PN 1
J 0
(-7038 5162);
DISPLAY 0.489362 (-7038 5162);
PAINT MONO (-7038 5162);
FORCEPROP 1 LASTPIN (-6850 5150) $PN 2
J 0
(-6888 5162);
DISPLAY 0.489362 (-6888 5162);
PAINT MONO (-6888 5162);
FORCEPROP 1 LAST VALUE 33
J 2
(-7050 5150);
DISPLAY 0.489362 (-7050 5150);
PAINT SKYBLUE (-7050 5150);
FORCEPROP 1 LAST PACK_TYPE 0402LF
J 0
(-6900 5075);
DISPLAY 0.489362 (-6900 5075);
PAINT SKYBLUE (-6900 5075);
DISPLAY INVISIBLE (-6900 5075);
FORCEPROP 1 LAST PART_NUMBER CS03302JB29
J 0
(-6925 5200);
DISPLAY 0.489362 (-6925 5200);
PAINT SKYBLUE (-6925 5200);
DISPLAY INVISIBLE (-6925 5200);
FORCEPROP 1 LAST TOLERANCE 5%
J 0
(-6975 5075);
DISPLAY 0.489362 (-6975 5075);
PAINT SKYBLUE (-6975 5075);
DISPLAY INVISIBLE (-6975 5075);
FORCEPROP 1 LAST MATERIAL CHIP
J 0
(-6525 5075);
DISPLAY 0.489362 (-6525 5075);
PAINT SKYBLUE (-6525 5075);
DISPLAY INVISIBLE (-6525 5075);
FORCEPROP 1 LAST WATTAGE 1/16W
J 2
(-6550 5075);
DISPLAY 0.489362 (-6550 5075);
PAINT SKYBLUE (-6550 5075);
DISPLAY INVISIBLE (-6550 5075);
FORCEPROP 1 LAST PATH I412
J 0
(-7000 5300);
DISPLAY 0.978723 (-7000 5300);
PAINT WHITE (-7000 5300);
DISPLAY INVISIBLE (-7000 5300);
FORCEPROP 2 LAST CDS_LIB pure_quanta
J 0
(-6950 5150);
DISPLAY INVISIBLE (-6950 5150);
FORCEADD Q_RES..1
(-6950 5100);
FORCEPROP 1 LAST LOCATION R467
J 0
(-6825 5100);
DISPLAY 0.489362 (-6825 5100);
PAINT SKYBLUE (-6825 5100);
FORCEPROP 0 LAST $SEC 1
J 0
(-6825 5125);
DISPLAY 0.680851 (-6825 5125);
PAINT MONO (-6825 5125);
DISPLAY INVISIBLE (-6825 5125);
FORCEPROP 0 LAST CDS_SEC 1
J 0
(-6825 5125);
DISPLAY 0.680851 (-6825 5125);
DISPLAY INVISIBLE (-6825 5125);
FORCEPROP 1 LASTPIN (-7050 5100) $PN 1
J 0
(-7038 5112);
DISPLAY 0.489362 (-7038 5112);
PAINT MONO (-7038 5112);
FORCEPROP 1 LASTPIN (-6850 5100) $PN 2
J 0
(-6888 5112);
DISPLAY 0.489362 (-6888 5112);
PAINT MONO (-6888 5112);
FORCEPROP 1 LAST VALUE 33
J 2
(-7050 5100);
DISPLAY 0.489362 (-7050 5100);
PAINT SKYBLUE (-7050 5100);
FORCEPROP 1 LAST PACK_TYPE 0402LF
J 0
(-6900 5025);
DISPLAY 0.489362 (-6900 5025);
PAINT SKYBLUE (-6900 5025);
DISPLAY INVISIBLE (-6900 5025);
FORCEPROP 1 LAST PART_NUMBER CS03302JB29
J 0
(-6925 5150);
DISPLAY 0.489362 (-6925 5150);
PAINT SKYBLUE (-6925 5150);
DISPLAY INVISIBLE (-6925 5150);
FORCEPROP 1 LAST TOLERANCE 5%
J 0
(-6975 5025);
DISPLAY 0.489362 (-6975 5025);
PAINT SKYBLUE (-6975 5025);
DISPLAY INVISIBLE (-6975 5025);
FORCEPROP 1 LAST MATERIAL CHIP
J 0
(-6525 5025);
DISPLAY 0.489362 (-6525 5025);
PAINT SKYBLUE (-6525 5025);
DISPLAY INVISIBLE (-6525 5025);
FORCEPROP 1 LAST WATTAGE 1/16W
J 2
(-6550 5025);
DISPLAY 0.489362 (-6550 5025);
PAINT SKYBLUE (-6550 5025);
DISPLAY INVISIBLE (-6550 5025);
FORCEPROP 1 LAST PATH I413
J 0
(-7000 5250);
DISPLAY 0.978723 (-7000 5250);
PAINT WHITE (-7000 5250);
DISPLAY INVISIBLE (-7000 5250);
FORCEPROP 2 LAST CDS_LIB pure_quanta
J 0
(-6950 5100);
DISPLAY INVISIBLE (-6950 5100);
FORCEADD Q_RES..1
(-6950 4250);
FORCEPROP 1 LAST LOCATION R475
J 0
(-6825 4250);
DISPLAY 0.489362 (-6825 4250);
PAINT SKYBLUE (-6825 4250);
FORCEPROP 0 LAST $SEC 1
J 0
(-6825 4275);
DISPLAY 0.680851 (-6825 4275);
PAINT MONO (-6825 4275);
DISPLAY INVISIBLE (-6825 4275);
FORCEPROP 0 LAST CDS_SEC 1
J 0
(-6825 4275);
DISPLAY 0.680851 (-6825 4275);
DISPLAY INVISIBLE (-6825 4275);
FORCEPROP 1 LASTPIN (-7050 4250) $PN 1
J 0
(-7038 4262);
DISPLAY 0.489362 (-7038 4262);
PAINT MONO (-7038 4262);
FORCEPROP 1 LASTPIN (-6850 4250) $PN 2
J 0
(-6888 4262);
DISPLAY 0.489362 (-6888 4262);
PAINT MONO (-6888 4262);
FORCEPROP 1 LAST VALUE 33
J 2
(-7050 4250);
DISPLAY 0.489362 (-7050 4250);
PAINT SKYBLUE (-7050 4250);
FORCEPROP 1 LAST PACK_TYPE 0402LF
J 0
(-6900 4175);
DISPLAY 0.489362 (-6900 4175);
PAINT SKYBLUE (-6900 4175);
DISPLAY INVISIBLE (-6900 4175);
FORCEPROP 1 LAST PART_NUMBER CS03302JB29
J 0
(-6925 4300);
DISPLAY 0.489362 (-6925 4300);
PAINT SKYBLUE (-6925 4300);
DISPLAY INVISIBLE (-6925 4300);
FORCEPROP 1 LAST TOLERANCE 5%
J 0
(-6975 4175);
DISPLAY 0.489362 (-6975 4175);
PAINT SKYBLUE (-6975 4175);
DISPLAY INVISIBLE (-6975 4175);
FORCEPROP 1 LAST MATERIAL CHIP
J 0
(-6525 4175);
DISPLAY 0.489362 (-6525 4175);
PAINT SKYBLUE (-6525 4175);
DISPLAY INVISIBLE (-6525 4175);
FORCEPROP 1 LAST WATTAGE 1/16W
J 2
(-6550 4175);
DISPLAY 0.489362 (-6550 4175);
PAINT SKYBLUE (-6550 4175);
DISPLAY INVISIBLE (-6550 4175);
FORCEPROP 1 LAST PATH I414
J 0
(-7000 4400);
DISPLAY 0.978723 (-7000 4400);
PAINT WHITE (-7000 4400);
DISPLAY INVISIBLE (-7000 4400);
FORCEPROP 2 LAST CDS_LIB pure_quanta
J 0
(-6950 4250);
DISPLAY INVISIBLE (-6950 4250);
FORCEADD Q_RES..1
(-6950 5600);
FORCEPROP 1 LAST $LOCATION R1592
J 0
(-6825 5600);
DISPLAY 0.489362 (-6825 5600);
PAINT SKYBLUE (-6825 5600);
FORCEPROP 0 LAST CDS_LOCATION R1592
J 0
(-6825 5625);
DISPLAY 0.680851 (-6825 5625);
DISPLAY INVISIBLE (-6825 5625);
FORCEPROP 0 LAST $SEC 1
J 0
(-6825 5625);
DISPLAY 0.680851 (-6825 5625);
PAINT MONO (-6825 5625);
DISPLAY INVISIBLE (-6825 5625);
FORCEPROP 0 LAST CDS_SEC 1
J 0
(-6825 5625);
DISPLAY 0.680851 (-6825 5625);
DISPLAY INVISIBLE (-6825 5625);
FORCEPROP 1 LASTPIN (-7050 5600) $PN 1
J 0
(-7038 5612);
DISPLAY 0.787234 (-7038 5612);
PAINT MONO (-7038 5612);
FORCEPROP 1 LASTPIN (-6850 5600) $PN 2
J 0
(-6888 5612);
DISPLAY 0.787234 (-6888 5612);
PAINT MONO (-6888 5612);
FORCEPROP 1 LAST VALUE 33
J 2
(-7050 5600);
DISPLAY 0.489362 (-7050 5600);
PAINT SKYBLUE (-7050 5600);
FORCEPROP 1 LAST MATERIAL EMPTY
J 0
(-7225 5600);
DISPLAY 0.489362 (-7225 5600);
PAINT RED (-7225 5600);
FORCEPROP 2 LAST CDS_LIB pure_quanta
J 0
(-6950 5600);
DISPLAY INVISIBLE (-6950 5600);
FORCEPROP 1 LAST PATH I415
J 0
(-7000 5750);
DISPLAY 0.978723 (-7000 5750);
PAINT WHITE (-7000 5750);
DISPLAY INVISIBLE (-7000 5750);
FORCEPROP 1 LAST PACK_TYPE 0402LF
J 0
(-6900 5525);
DISPLAY 0.489362 (-6900 5525);
PAINT SKYBLUE (-6900 5525);
DISPLAY INVISIBLE (-6900 5525);
FORCEPROP 1 LAST PART_NUMBER CS03302JB29
J 0
(-6925 5650);
DISPLAY 0.489362 (-6925 5650);
PAINT SKYBLUE (-6925 5650);
DISPLAY INVISIBLE (-6925 5650);
FORCEPROP 1 LAST TOLERANCE 5%
J 0
(-6975 5525);
DISPLAY 0.489362 (-6975 5525);
PAINT SKYBLUE (-6975 5525);
DISPLAY INVISIBLE (-6975 5525);
FORCEPROP 1 LAST WATTAGE 1/16W
J 2
(-6550 5525);
DISPLAY 0.489362 (-6550 5525);
PAINT SKYBLUE (-6550 5525);
DISPLAY INVISIBLE (-6550 5525);
FORCEADD Q_RES..1
(-6950 4500);
FORCEPROP 1 LAST $LOCATION R1593
J 0
(-6825 4500);
DISPLAY 0.489362 (-6825 4500);
PAINT SKYBLUE (-6825 4500);
FORCEPROP 0 LAST CDS_LOCATION R1593
J 0
(-6825 4525);
DISPLAY 0.680851 (-6825 4525);
DISPLAY INVISIBLE (-6825 4525);
FORCEPROP 0 LAST $SEC 1
J 0
(-6825 4525);
DISPLAY 0.680851 (-6825 4525);
PAINT MONO (-6825 4525);
DISPLAY INVISIBLE (-6825 4525);
FORCEPROP 0 LAST CDS_SEC 1
J 0
(-6825 4525);
DISPLAY 0.680851 (-6825 4525);
DISPLAY INVISIBLE (-6825 4525);
FORCEPROP 1 LASTPIN (-7050 4500) $PN 1
J 0
(-7038 4512);
DISPLAY 0.787234 (-7038 4512);
PAINT MONO (-7038 4512);
FORCEPROP 1 LASTPIN (-6850 4500) $PN 2
J 0
(-6888 4512);
DISPLAY 0.787234 (-6888 4512);
PAINT MONO (-6888 4512);
FORCEPROP 1 LAST VALUE 33
J 2
(-7050 4500);
DISPLAY 0.489362 (-7050 4500);
PAINT SKYBLUE (-7050 4500);
FORCEPROP 1 LAST MATERIAL EMPTY
J 0
(-7200 4500);
DISPLAY 0.489362 (-7200 4500);
PAINT RED (-7200 4500);
FORCEPROP 1 LAST PACK_TYPE 0402LF
J 0
(-6900 4425);
DISPLAY 0.489362 (-6900 4425);
PAINT SKYBLUE (-6900 4425);
DISPLAY INVISIBLE (-6900 4425);
FORCEPROP 1 LAST PART_NUMBER CS03302JB29
J 0
(-6925 4550);
DISPLAY 0.489362 (-6925 4550);
PAINT SKYBLUE (-6925 4550);
DISPLAY INVISIBLE (-6925 4550);
FORCEPROP 1 LAST TOLERANCE 5%
J 0
(-6975 4425);
DISPLAY 0.489362 (-6975 4425);
PAINT SKYBLUE (-6975 4425);
DISPLAY INVISIBLE (-6975 4425);
FORCEPROP 1 LAST WATTAGE 1/16W
J 2
(-6550 4425);
DISPLAY 0.489362 (-6550 4425);
PAINT SKYBLUE (-6550 4425);
DISPLAY INVISIBLE (-6550 4425);
FORCEPROP 1 LAST PATH I416
J 0
(-7000 4650);
DISPLAY 0.978723 (-7000 4650);
PAINT WHITE (-7000 4650);
DISPLAY INVISIBLE (-7000 4650);
FORCEPROP 2 LAST CDS_LIB pure_quanta
J 0
(-6950 4500);
DISPLAY INVISIBLE (-6950 4500);
FORCEADD QUANTA_TITLE_BLOCK_C..1
(-100 100);
FORCEPROP 0 LAST CDS_CON_LAST_MODIFIED Fri Mar 11 14:52:22 2022
J 0
(-1985 115);
DISPLAY INVISIBLE (-1985 115);
FORCEPROP 1 LAST CUSTOM_TXT_CDS <CON_LAST_MODIFIED>
J 0
(-1985 115);
DISPLAY 0.978723 (-1985 115);
FORCEPROP 2 LAST CUSTOM_TXT_CDS <XR_PAGE_TITLE>
J 0
(-7990 5350);
DISPLAY 0.638298 (-7990 5350);
PAINT PINK (-7990 5350);
DISPLAY INVISIBLE (-7990 5350);
FORCEPROP 1 LAST CUSTOM_TXT_CDS <NAME_2>
J 0
(-3275 150);
FORCEPROP 1 LAST CUSTOM_TXT_CDS <NAME_1>
J 0
(-3275 275);
FORCEPROP 1 LAST CUSTOM_TXT_CDS <Q_NUMBER>
J 0
(-1503 203);
DISPLAY 1.212766 (-1503 203);
FORCEPROP 1 LAST CUSTOM_TXT_CDS <Q_PROJ>
J 0
(-2482 202);
DISPLAY 1.212766 (-2482 202);
FORCEPROP 1 LAST CUSTOM_TXT_CDS <Q_REV>
J 0
(-284 203);
DISPLAY 1.212766 (-284 203);
FORCEPROP 1 LAST CUSTOM_TXT_CDS <CON_PAGE_NUM> OF <CON_TOTAL_PAGES>
J 0
(-546 118);
DISPLAY 0.978723 (-546 118);
FORCEPROP 1 LAST Q_TITLE CPU0 SPI/USB
J 0
(-9400 150);
DISPLAY 2.446809 (-9400 150);
PAINT GREEN (-9400 150);
FORCEPROP 1 LAST Q_DEPT BU9
J 1
(-3863 149);
DISPLAY 1.957447 (-3863 149);
PAINT GREEN (-3863 149);
FORCEPROP 1 LAST COMMENT_BODY TRUE
J 0
(-88 87);
DISPLAY 0.978723 (-88 87);
PAINT GREEN (-88 87);
DISPLAY INVISIBLE (-88 87);
FORCEPROP 2 LAST CDS_LIB pure_quanta
J 0
(-100 100);
DISPLAY INVISIBLE (-100 100);
FORCEPROP 1 LAST CDS_LMAN_SYM_OUTLINE -9475,6775,100,-125
J 0
(-100 100);
DISPLAY 0.468085 (-100 100);
PAINT GREEN (-100 100);
DISPLAY INVISIBLE (-100 100);
FORCEPROP 2 LAST PAGE_BORDER TRUE
J 0
(-7990 5350);
DISPLAY 0.638298 (-7990 5350);
PAINT PINK (-7990 5350);
DISPLAY INVISIBLE (-7990 5350);
FORCEPROP 2 LAST CDS_XR_PAGE_TITLE CR-29 : @T6G_MB_LIB.T6G(SCH_1):PAGE29
J 0
(-7990 5350);
DISPLAY 0.638298 (-7990 5350);
PAINT PINK (-7990 5350);
DISPLAY INVISIBLE (-7990 5350);
FORCEADD DNS..2
(-6975 5600);
PAINT RED (-6975 5600);
FORCEPROP 1 LAST COMMENT_BODY TRUE
J 0
(-6975 5600);
PAINT RED (-6975 5600);
DISPLAY INVISIBLE (-6975 5600);
FORCEPROP 2 LAST CDS_LIB mstr_misc
J 0
(-6975 5600);
DISPLAY INVISIBLE (-6975 5600);
FORCEADD DNS..2
(-6975 4525);
PAINT RED (-6975 4525);
FORCEPROP 1 LAST COMMENT_BODY TRUE
J 0
(-6975 4525);
PAINT RED (-6975 4525);
DISPLAY INVISIBLE (-6975 4525);
FORCEPROP 2 LAST CDS_LIB mstr_misc
J 0
(-6975 4525);
DISPLAY INVISIBLE (-6975 4525);
WIRE 16 -1 (-2975 2750)(-2975 2700);
WIRE 16 -1 (-1600 3050)(-1600 3175);
WIRE 16 -1 (-7050 4500)(-7200 4500);
WIRE 16 -1 (-7200 4500)(-7200 4650);
WIRE 16 -1 (-7050 4650)(-7200 4650);
WIRE 16 -1 (-7200 4650)(-7725 4650);
FORCEPROP 2 LAST SIG_NAME ESPI_CPU0_ALERT_N
J 0
(-7610 4660);
DISPLAY 0.489362 (-7610 4660);
WIRE 16 -1 (-6850 4500)(-5925 4500);
FORCEPROP 2 LAST SIG_NAME CPU0_ESPI0_ALERT_N
J 0
(-6685 4510);
DISPLAY 0.489362 (-6685 4510);
FORCEPROP 2 LASTPROP $XRERR UNIQUE?
J 0
(-6925 4510);
DISPLAY 0.638298 (-6925 4510);
PAINT MONO (-6925 4510);
DISPLAY INVISIBLE (-6925 4510);
WIRE 16 -1 (-6850 4800)(-5925 4800);
FORCEPROP 2 LAST SIG_NAME ESPI_CPU0_R_D3
J 0
(-6685 4810);
DISPLAY 0.489362 (-6685 4810);
FORCEPROP 2 LASTPROP $XRERR UNIQUE?
J 0
(-6925 4810);
DISPLAY 0.638298 (-6925 4810);
PAINT MONO (-6925 4810);
DISPLAY INVISIBLE (-6925 4810);
WIRE 16 -1 (-6850 4650)(-5925 4650);
FORCEPROP 2 LAST SIG_NAME ESPI_CPU0_R_ALERT_N
J 0
(-6685 4660);
DISPLAY 0.489362 (-6685 4660);
FORCEPROP 2 LASTPROP $XRERR UNIQUE?
J 0
(-6925 4660);
DISPLAY 0.638298 (-6925 4660);
PAINT MONO (-6925 4660);
DISPLAY INVISIBLE (-6925 4660);
WIRE 16 -1 (-6850 4450)(-5925 4450);
FORCEPROP 2 LAST SIG_NAME CLK_ESPI_CPU0_R_CLK1
J 0
(-6685 4460);
DISPLAY 0.489362 (-6685 4460);
FORCEPROP 2 LASTPROP $XRERR UNIQUE?
J 0
(-6925 4460);
DISPLAY 0.638298 (-6925 4460);
PAINT MONO (-6925 4460);
DISPLAY INVISIBLE (-6925 4460);
WIRE 16 -1 (-7725 4400)(-5925 4400);
FORCEPROP 2 LAST SIG_NAME PD_ESPI_CPU0_CLK2
J 0
(-7610 4410);
DISPLAY 0.489362 (-7610 4410);
WIRE 16 -1 (-6850 5550)(-5925 5550);
FORCEPROP 2 LAST SIG_NAME ESPI_CPU0_R_CS1_N
J 0
(-6685 5560);
DISPLAY 0.489362 (-6685 5560);
FORCEPROP 2 LASTPROP $XRERR UNIQUE?
J 0
(-6925 5560);
DISPLAY 0.638298 (-6925 5560);
PAINT MONO (-6925 5560);
DISPLAY INVISIBLE (-6925 5560);
WIRE 16 -1 (-7725 5450)(-5925 5450);
FORCEPROP 2 LAST SIG_NAME RST_CPU0_KBRST_R_N
J 0
(-6685 5460);
DISPLAY 0.489362 (-6685 5460);
WIRE 16 -1 (-6850 4850)(-5925 4850);
FORCEPROP 2 LAST SIG_NAME ESPI_CPU0_R_D2
J 0
(-6685 4860);
DISPLAY 0.489362 (-6685 4860);
FORCEPROP 2 LASTPROP $XRERR UNIQUE?
J 0
(-6925 4860);
DISPLAY 0.638298 (-6925 4860);
PAINT MONO (-6925 4860);
DISPLAY INVISIBLE (-6925 4860);
WIRE 16 -1 (-7725 4900)(-7050 4900);
FORCEPROP 2 LAST SIG_NAME ESPI_CPU0_D1
J 0
(-7610 4910);
DISPLAY 0.489362 (-7610 4910);
WIRE 16 -1 (-7725 5200)(-7050 5200);
FORCEPROP 2 LAST SIG_NAME SPI_CPU0_D1
J 0
(-7610 5210);
DISPLAY 0.489362 (-7610 5210);
WIRE 16 -1 (-7050 4450)(-7725 4450);
FORCEPROP 2 LAST SIG_NAME CLK_ESPI_CPU0_CLK1
J 0
(-7610 4460);
DISPLAY 0.489362 (-7610 4460);
WIRE 16 -1 (-6850 4350)(-5925 4350);
FORCEPROP 2 LAST SIG_NAME RST_ESPI_CPU0_R_RSTOUT_N
J 0
(-6685 4360);
DISPLAY 0.489362 (-6685 4360);
FORCEPROP 2 LASTPROP $XRERR UNIQUE?
J 0
(-6925 4360);
DISPLAY 0.638298 (-6925 4360);
PAINT MONO (-6925 4360);
DISPLAY INVISIBLE (-6925 4360);
WIRE 16 -1 (-6850 4250)(-5925 4250);
FORCEPROP 2 LAST SIG_NAME SPI_CPU0_R_TPM_CS_N
J 0
(-6685 4260);
DISPLAY 0.489362 (-6685 4260);
FORCEPROP 2 LASTPROP $XRERR UNIQUE?
J 0
(-6925 4260);
DISPLAY 0.638298 (-6925 4260);
PAINT MONO (-6925 4260);
DISPLAY INVISIBLE (-6925 4260);
WIRE 16 -1 (-7050 4850)(-7725 4850);
FORCEPROP 2 LAST SIG_NAME ESPI_CPU0_D2
J 0
(-7610 4860);
DISPLAY 0.489362 (-7610 4860);
WIRE 16 -1 (-7050 5100)(-7725 5100);
FORCEPROP 2 LAST SIG_NAME SPI_CPU0_D3
J 0
(-7610 5110);
DISPLAY 0.489362 (-7610 5110);
WIRE 16 -1 (-7050 5150)(-7725 5150);
FORCEPROP 2 LAST SIG_NAME SPI_CPU0_D2
J 0
(-7610 5160);
DISPLAY 0.489362 (-7610 5160);
WIRE 16 -1 (-7725 5250)(-7050 5250);
FORCEPROP 2 LAST SIG_NAME SPI_CPU0_D0
J 0
(-7610 5260);
DISPLAY 0.489362 (-7610 5260);
WIRE 16 -1 (-7050 4350)(-7725 4350);
FORCEPROP 2 LAST SIG_NAME RST_ESPI_CPU0_RSTOUT_N
J 0
(-7610 4360);
DISPLAY 0.489362 (-7610 4360);
WIRE 16 -1 (-3425 4250)(-2525 4250);
FORCEPROP 2 LAST SIG_NAME USB3_CPU0_P10_TX_DN
J 0
(-3210 4260);
DISPLAY 0.489362 (-3210 4260);
FORCEPROP 2 LASTPROP $XRERR UNIQUE?
J 0
(-3450 4260);
DISPLAY 0.638298 (-3450 4260);
PAINT MONO (-3450 4260);
DISPLAY INVISIBLE (-3450 4260);
WIRE 16 -1 (-1275 3950)(-3425 3950);
FORCEPROP 2 LAST SIG_NAME SCM_USB_OC_BUF_N
J 0
(-1760 3960);
DISPLAY 0.489362 (-1760 3960);
WIRE 16 -1 (-3425 3850)(-1275 3850);
FORCEPROP 0 LAST SIG_NAME USB_OC_N
J 2
(-1300 3860);
DISPLAY 0.489362 (-1300 3860);
WIRE 16 -1 (-7725 5550)(-7225 5550);
FORCEPROP 2 LAST SIG_NAME ESPI_CPU0_CS1_N
J 0
(-7610 5560);
DISPLAY 0.489362 (-7610 5560);
WIRE 16 -1 (-7225 5550)(-7050 5550);
WIRE 16 -1 (-7225 5600)(-7225 5550);
WIRE 16 -1 (-7050 5600)(-7225 5600);
WIRE 16 -1 (-6850 4950)(-5925 4950);
FORCEPROP 2 LAST SIG_NAME ESPI_CPU0_R_D0
J 0
(-6685 4960);
DISPLAY 0.489362 (-6685 4960);
FORCEPROP 2 LASTPROP $XRERR UNIQUE?
J 0
(-6925 4960);
DISPLAY 0.638298 (-6925 4960);
PAINT MONO (-6925 4960);
DISPLAY INVISIBLE (-6925 4960);
WIRE 16 -1 (-6850 5150)(-5925 5150);
FORCEPROP 2 LAST SIG_NAME SPI_CPU0_R_D2
J 0
(-6685 5160);
DISPLAY 0.489362 (-6685 5160);
FORCEPROP 2 LASTPROP $XRERR UNIQUE?
J 0
(-6925 5160);
DISPLAY 0.638298 (-6925 5160);
PAINT MONO (-6925 5160);
DISPLAY INVISIBLE (-6925 5160);
WIRE 16 -1 (-6850 5200)(-5925 5200);
FORCEPROP 2 LAST SIG_NAME SPI_CPU0_R_D1
J 0
(-6685 5210);
DISPLAY 0.489362 (-6685 5210);
FORCEPROP 2 LASTPROP $XRERR UNIQUE?
J 0
(-6925 5210);
DISPLAY 0.638298 (-6925 5210);
PAINT MONO (-6925 5210);
DISPLAY INVISIBLE (-6925 5210);
WIRE 16 -1 (-6850 5600)(-5925 5600);
FORCEPROP 2 LAST SIG_NAME CPU0_ESPI_CS0_N
J 0
(-6685 5610);
DISPLAY 0.489362 (-6685 5610);
FORCEPROP 2 LASTPROP $XRERR UNIQUE?
J 0
(-6925 5610);
DISPLAY 0.638298 (-6925 5610);
PAINT MONO (-6925 5610);
DISPLAY INVISIBLE (-6925 5610);
WIRE 16 -1 (-6850 5650)(-5925 5650);
FORCEPROP 2 LAST SIG_NAME SPI_CPU0_R_CLK
J 0
(-6685 5660);
DISPLAY 0.489362 (-6685 5660);
FORCEPROP 2 LASTPROP $XRERR UNIQUE?
J 0
(-6925 5660);
DISPLAY 0.638298 (-6925 5660);
PAINT MONO (-6925 5660);
DISPLAY INVISIBLE (-6925 5660);
WIRE 16 -1 (-6850 5800)(-5925 5800);
FORCEPROP 2 LAST SIG_NAME NC_CPU0_SPI_CS2_N
J 0
(-6685 5810);
DISPLAY 0.489362 (-6685 5810);
FORCEPROP 2 LASTPROP $XRERR UNIQUE?
J 0
(-7090 5800);
DISPLAY 0.638298 (-7090 5800);
PAINT MONO (-7090 5800);
DISPLAY INVISIBLE (-7090 5800);
WIRE 16 -1 (-6850 5850)(-5925 5850);
FORCEPROP 2 LAST SIG_NAME SPI_CPU0_R_CS1_N
J 0
(-6685 5860);
DISPLAY 0.489362 (-6685 5860);
FORCEPROP 2 LASTPROP $XRERR UNIQUE?
J 0
(-6925 5860);
DISPLAY 0.638298 (-6925 5860);
PAINT MONO (-6925 5860);
DISPLAY INVISIBLE (-6925 5860);
WIRE 16 -1 (-6850 5900)(-5925 5900);
FORCEPROP 2 LAST SIG_NAME SPI_CPU0_R_CS0_N
J 0
(-6685 5910);
DISPLAY 0.489362 (-6685 5910);
FORCEPROP 2 LASTPROP $XRERR UNIQUE?
J 0
(-6925 5910);
DISPLAY 0.638298 (-6925 5910);
PAINT MONO (-6925 5910);
DISPLAY INVISIBLE (-6925 5910);
WIRE 16 -1 (-8125 2575)(-8125 2375);
WIRE 16 -1 (-8125 2375)(-7850 2375);
WIRE 16 -1 (-8125 2325)(-8125 2375);
WIRE 16 -1 (-7850 2325)(-8125 2325);
WIRE 16 -1 (-8125 2275)(-8125 2325);
WIRE 16 -1 (-7850 2275)(-8125 2275);
WIRE 16 -1 (-8125 2225)(-8125 2275);
WIRE 16 -1 (-7850 2225)(-8125 2225);
WIRE 16 -1 (-8125 2225)(-8125 2150);
WIRE 16 -1 (-8125 2150)(-7850 2150);
WIRE 16 -1 (-2900 2650)(-2800 2650);
WIRE 16 -1 (-2900 3025)(-2900 2650);
WIRE 16 -1 (-2900 3075)(-2900 3025);
WIRE 16 -1 (-2975 3025)(-2900 3025);
WIRE 16 -1 (-2975 2950)(-2975 3025);
WIRE 16 -1 (-2875 2375)(-2875 2450);
WIRE 16 -1 (-2875 2450)(-2800 2450);
WIRE 16 -1 (-7925 3525)(-7925 3625);
WIRE 16 -1 (-7925 3325)(-7925 3525);
WIRE 16 -1 (-8150 3525)(-7925 3525);
WIRE 16 -1 (-8150 3350)(-8150 3525);
WIRE 16 -1 (-7050 5900)(-7725 5900);
FORCEPROP 2 LAST SIG_NAME SPI_CPU0_CS0_N
J 0
(-7610 5910);
DISPLAY 0.489362 (-7610 5910);
WIRE 16 -1 (-7050 5850)(-7725 5850);
FORCEPROP 2 LAST SIG_NAME SPI_CPU0_CS1_N
J 0
(-7610 5860);
DISPLAY 0.489362 (-7610 5860);
WIRE 16 -1 (-6850 5250)(-5925 5250);
FORCEPROP 2 LAST SIG_NAME SPI_CPU0_R_D0
J 0
(-6685 5260);
DISPLAY 0.489362 (-6685 5260);
FORCEPROP 2 LASTPROP $XRERR UNIQUE?
J 0
(-6925 5260);
DISPLAY 0.638298 (-6925 5260);
PAINT MONO (-6925 5260);
DISPLAY INVISIBLE (-6925 5260);
WIRE 16 -1 (-6850 5100)(-5925 5100);
FORCEPROP 2 LAST SIG_NAME SPI_CPU0_R_D3
J 0
(-6685 5110);
DISPLAY 0.489362 (-6685 5110);
FORCEPROP 2 LASTPROP $XRERR UNIQUE?
J 0
(-6925 5110);
DISPLAY 0.638298 (-6925 5110);
PAINT MONO (-6925 5110);
DISPLAY INVISIBLE (-6925 5110);
WIRE 16 -1 (-6850 4900)(-5925 4900);
FORCEPROP 2 LAST SIG_NAME ESPI_CPU0_R_D1
J 0
(-6685 4910);
DISPLAY 0.489362 (-6685 4910);
FORCEPROP 2 LASTPROP $XRERR UNIQUE?
J 0
(-6925 4910);
DISPLAY 0.638298 (-6925 4910);
PAINT MONO (-6925 4910);
DISPLAY INVISIBLE (-6925 4910);
WIRE 16 -1 (-7725 5650)(-7050 5650);
FORCEPROP 2 LAST SIG_NAME SPI_CPU0_CLK
J 0
(-7610 5660);
DISPLAY 0.489362 (-7610 5660);
WIRE 16 -1 (-7050 4800)(-7725 4800);
FORCEPROP 2 LAST SIG_NAME ESPI_CPU0_D3
J 0
(-7610 4810);
DISPLAY 0.489362 (-7610 4810);
WIRE 16 -1 (-7725 4950)(-7050 4950);
FORCEPROP 2 LAST SIG_NAME ESPI_CPU0_D0
J 0
(-7610 4960);
DISPLAY 0.489362 (-7610 4960);
WIRE 16 -1 (-7050 4250)(-7725 4250);
FORCEPROP 2 LAST SIG_NAME SPI_CPU0_TPM_CS_N
J 0
(-7610 4260);
DISPLAY 0.489362 (-7610 4260);
WIRE 16 -1 (-7650 2325)(-6900 2325);
FORCEPROP 2 LAST SIG_NAME ESPI_CPU0_D1
J 0
(-7310 2335);
DISPLAY 0.489362 (-7310 2335);
WIRE 16 -1 (-2375 4300)(-1275 4300);
FORCEPROP 2 LAST SIG_NAME USB3_CPU0_P10_TX_C_DP
J 0
(-1835 4310);
DISPLAY 0.489362 (-1835 4310);
WIRE 16 -1 (-2350 4900)(-1250 4900);
FORCEPROP 2 LAST SIG_NAME USB3_CPU0_P10_RX_DN
J 0
(-1835 4910);
DISPLAY 0.489362 (-1835 4910);
WIRE 16 -1 (-2375 4250)(-1275 4250);
FORCEPROP 2 LAST SIG_NAME USB3_CPU0_P10_TX_C_DN
J 0
(-1835 4260);
DISPLAY 0.489362 (-1835 4260);
WIRE 16 -1 (-3425 5850)(-2525 5850);
FORCEPROP 2 LAST SIG_NAME USB2_CPU0_P0_DN
J 0
(-3160 5860);
DISPLAY 0.489362 (-3160 5860);
WIRE 16 -1 (-3425 5900)(-2525 5900);
FORCEPROP 2 LAST SIG_NAME USB2_CPU0_P0_DP
J 0
(-3160 5910);
DISPLAY 0.489362 (-3160 5910);
WIRE 16 -1 (-3425 4300)(-2525 4300);
FORCEPROP 2 LAST SIG_NAME USB3_CPU0_P10_TX_DP
J 0
(-3210 4310);
DISPLAY 0.489362 (-3210 4310);
FORCEPROP 2 LASTPROP $XRERR UNIQUE?
J 0
(-3450 4310);
DISPLAY 0.638298 (-3450 4310);
PAINT MONO (-3450 4310);
DISPLAY INVISIBLE (-3450 4310);
WIRE 16 -1 (-3425 4950)(-2500 4950);
FORCEPROP 2 LAST SIG_NAME USB3_CPU0_P10_RX_C_DP
J 0
(-3235 4960);
DISPLAY 0.489362 (-3235 4960);
FORCEPROP 2 LASTPROP $XRERR UNIQUE?
J 0
(-3475 4960);
DISPLAY 0.638298 (-3475 4960);
PAINT MONO (-3475 4960);
DISPLAY INVISIBLE (-3475 4960);
WIRE 16 -1 (-3425 4900)(-2500 4900);
FORCEPROP 2 LAST SIG_NAME USB3_CPU0_P10_RX_C_DN
J 0
(-3235 4910);
DISPLAY 0.489362 (-3235 4910);
FORCEPROP 2 LASTPROP $XRERR UNIQUE?
J 0
(-3475 4910);
DISPLAY 0.638298 (-3475 4910);
PAINT MONO (-3475 4910);
DISPLAY INVISIBLE (-3475 4910);
WIRE 16 -1 (-925 2550)(-1600 2550);
FORCEPROP 2 LAST SIG_NAME SCM_USB_OC_BUF_N
J 0
(-1535 2560);
DISPLAY 0.489362 (-1535 2560);
WIRE 16 -1 (-1600 2850)(-1600 2550);
WIRE 16 -1 (-1600 2550)(-1675 2550);
WIRE 16 -1 (-2450 2550)(-1875 2550);
FORCEPROP 2 LAST SIG_NAME SCM_USB_OC_BU_R_N
J 0
(-2385 2560);
DISPLAY 0.489362 (-2385 2560);
FORCEPROP 2 LASTPROP $XRERR UNIQUE?
J 0
(-2625 2560);
DISPLAY 0.638298 (-2625 2560);
PAINT MONO (-2625 2560);
DISPLAY INVISIBLE (-2625 2560);
WIRE 16 -1 (-2800 2550)(-3800 2550);
FORCEPROP 2 LAST SIG_NAME SCM_USB_OC_N
J 2
(-3310 2560);
DISPLAY 0.489362 (-3310 2560);
WIRE 16 -1 (-6875 2150)(-7650 2150);
FORCEPROP 2 LAST SIG_NAME ESPI_CPU0_ALERT_N
J 0
(-7310 2160);
DISPLAY 0.489362 (-7310 2160);
WIRE 16 -1 (-6900 2875)(-7925 2875);
FORCEPROP 2 LAST SIG_NAME RST_ESPI_CPU0_RSTOUT_N
J 0
(-7535 2885);
DISPLAY 0.489362 (-7535 2885);
WIRE 16 -1 (-7925 3125)(-7925 2875);
WIRE 16 -1 (-6900 2275)(-7650 2275);
FORCEPROP 2 LAST SIG_NAME ESPI_CPU0_D2
J 0
(-7310 2285);
DISPLAY 0.489362 (-7310 2285);
WIRE 16 -1 (-2350 4950)(-1250 4950);
FORCEPROP 2 LAST SIG_NAME USB3_CPU0_P10_RX_DP
J 0
(-1835 4960);
DISPLAY 0.489362 (-1835 4960);
WIRE 16 -1 (-6900 2225)(-7650 2225);
FORCEPROP 2 LAST SIG_NAME ESPI_CPU0_D3
J 0
(-7310 2235);
DISPLAY 0.489362 (-7310 2235);
WIRE 16 -1 (-7650 2375)(-6900 2375);
FORCEPROP 2 LAST SIG_NAME ESPI_CPU0_D0
J 0
(-7310 2385);
DISPLAY 0.489362 (-7310 2385);
WIRE 16 -1 (-6900 2775)(-8150 2775);
FORCEPROP 2 LAST SIG_NAME ESPI_CPU0_CS1_N
J 0
(-7535 2785);
DISPLAY 0.489362 (-7535 2785);
WIRE 16 -1 (-8150 3150)(-8150 2775);
WIRE 16 -1 (-3425 5750)(-2525 5750);
FORCEPROP 2 LAST SIG_NAME USB2_CPU0_P1_DP
J 0
(-3160 5760);
DISPLAY 0.489362 (-3160 5760);
WIRE 16 -1 (-3425 5700)(-2525 5700);
FORCEPROP 2 LAST SIG_NAME USB2_CPU0_P1_DN
J 0
(-3160 5710);
DISPLAY 0.489362 (-3160 5710);
WIRE 16 -1 (-3425 5600)(-2525 5600);
FORCEPROP 2 LAST SIG_NAME USB2_CPU0_P10_DP
J 0
(-3160 5610);
DISPLAY 0.489362 (-3160 5610);
WIRE 16 -1 (-3425 5550)(-2525 5550);
FORCEPROP 2 LAST SIG_NAME USB2_CPU0_P10_DN
J 0
(-3160 5560);
DISPLAY 0.489362 (-3160 5560);
DOT 1 (-7200 4650);
DOT 1 (-8125 2375);
DOT 1 (-8125 2275);
DOT 1 (-8125 2325);
DOT 1 (-1600 2550);
DOT 1 (-2900 3025);
DOT 1 (-7925 3525);
DOT 1 (-8125 2225);
DOT 1 (-7225 5550);
FORCENOTE
CAD NOTE: R472 R1593 CO-LAY
(-7350 4700) 0;
DISPLAY LEFT (-7350 4700);
DISPLAY 1.021277 (-7350 4700);
FORCENOTE
CAD NOTE: R462 R1592 CO-LAY
(-7350 5475) 0;
DISPLAY LEFT (-7350 5475);
DISPLAY 1.021277 (-7350 5475);
QUIT
